FILE_TYPE = MACRO_DRAWING;
SET COLOR_WIRE YELLOW;
SET COLOR_PROP MONO;
SET COLOR_DOT WHITE;
SET COLOR_ARC YELLOW;
SET COLOR_BODY GREEN;
SET COLOR_NOTE MONO;
SET PROP_DISPLAY VALUE;
SET PAGE_NUMBER P218;
FORCEADD OFFPAGE..2
(3950 1550);
FORCEPROP 2 LAST $XR0 218 
J 0
(4139 1550);
DISPLAY 0.638298 (4139 1550);
PAINT MONO (4139 1550);
FORCEPROP 2 LAST ROOM VDDQ_DEF_PWR_VR
J 0
(3525 1625);
DISPLAY 1.361702 (3525 1625);
PAINT ORANGE (3525 1625);
DISPLAY INVISIBLE (3525 1625);
FORCEPROP 1 LAST COMMENT_BODY TRUE
J 0
(3905 1455);
DISPLAY 1.170213 (3905 1455);
PAINT GREEN (3905 1455);
DISPLAY INVISIBLE (3905 1455);
FORCEPROP 2 LAST CDS_LIB mstr_standard
J 0
(3950 1550);
PAINT ORANGE (3950 1550);
DISPLAY INVISIBLE (3950 1550);
FORCEPROP 1 LAST OFFPAGE TRUE
J 0
(4275 1425);
DISPLAY 1.170213 (4275 1425);
PAINT GREEN (4275 1425);
DISPLAY INVISIBLE (4275 1425);
FORCEPROP 2 LAST PATH I1
J 0
(4150 1600);
DISPLAY 1.021277 (4150 1600);
PAINT ORANGE (4150 1600);
DISPLAY INVISIBLE (4150 1600);
FORCEADD OFFPAGE..2
(3925 2200);
FORCEPROP 2 LAST $XR0 194 
J 0
(4114 2200);
DISPLAY 0.638298 (4114 2200);
PAINT MONO (4114 2200);
FORCEPROP 2 LAST $XR1 215 
J 0
(4234 2200);
DISPLAY 0.638298 (4234 2200);
PAINT MONO (4234 2200);
FORCEPROP 2 LAST $XR2 21 
J 0
(4354 2200);
DISPLAY 0.638298 (4354 2200);
PAINT MONO (4354 2200);
FORCEPROP 2 LAST ROOM VDDQ_DEF_PWR_VR
J 0
(3500 2275);
DISPLAY 1.361702 (3500 2275);
PAINT ORANGE (3500 2275);
DISPLAY INVISIBLE (3500 2275);
FORCEPROP 1 LAST COMMENT_BODY TRUE
J 0
(3880 2105);
DISPLAY 1.170213 (3880 2105);
PAINT GREEN (3880 2105);
DISPLAY INVISIBLE (3880 2105);
FORCEPROP 2 LAST CDS_LIB mstr_standard
J 0
(3925 2200);
PAINT ORANGE (3925 2200);
DISPLAY INVISIBLE (3925 2200);
FORCEPROP 1 LAST OFFPAGE TRUE
J 0
(4250 2075);
DISPLAY 1.170213 (4250 2075);
PAINT GREEN (4250 2075);
DISPLAY INVISIBLE (4250 2075);
FORCEPROP 2 LAST PATH I10
J 0
(4250 2250);
DISPLAY 1.021277 (4250 2250);
PAINT ORANGE (4250 2250);
DISPLAY INVISIBLE (4250 2250);
FORCEADD RES..1
(3100 2350);
FORCEPROP 1 LAST WATTAGE 1/16W
J 2
(3025 2375);
DISPLAY 0.617021 (3025 2375);
PAINT SKYBLUE (3025 2375);
FORCEPROP 1 LAST MATERIAL CHIP
J 0
(2900 2425);
DISPLAY 0.617021 (2900 2425);
PAINT SKYBLUE (2900 2425);
FORCEPROP 1 LAST VALUE 22.1
J 2
(3025 2325);
DISPLAY 0.617021 (3025 2325);
PAINT SKYBLUE (3025 2325);
FORCEPROP 1 LAST PART_NUMBER G21796-250
J 0
(3050 2450);
DISPLAY 0.617021 (3050 2450);
PAINT BLUE (3050 2450);
FORCEPROP 1 LAST LOCATION R3M3
J 0
(3050 2400);
DISPLAY 0.617021 (3050 2400);
PAINT AQUA (3050 2400);
FORCEPROP 1 LAST PACK_TYPE 0402
J 0
(3200 2350);
DISPLAY 0.617021 (3200 2350);
PAINT SKYBLUE (3200 2350);
FORCEPROP 1 LAST TOLERANCE 1.0%
J 0
(3175 2325);
DISPLAY 0.617021 (3175 2325);
PAINT SKYBLUE (3175 2325);
FORCEPROP 1 LASTPIN (3000 2350) $PN 1
J 0
(3012 2362);
DISPLAY 0.787234 (3012 2362);
PAINT ORANGE (3012 2362);
DISPLAY INVISIBLE (3012 2362);
FORCEPROP 2 LAST ROOM VDDQ_DEF_PWR_VR
J 0
(3050 2450);
DISPLAY 1.361702 (3050 2450);
PAINT ORANGE (3050 2450);
DISPLAY INVISIBLE (3050 2450);
FORCEPROP 1 LAST PATH I11
J 0
(3050 2500);
DISPLAY 0.978723 (3050 2500);
PAINT WHITE (3050 2500);
DISPLAY INVISIBLE (3050 2500);
FORCEPROP 2 LAST CDS_LOCATION R3M3
J 0
(3050 2400);
DISPLAY 0.617021 (3050 2400);
PAINT AQUA (3050 2400);
DISPLAY INVISIBLE (3050 2400);
FORCEPROP 2 LAST $SEC 1
J 0
(3050 2550);
PAINT MONO (3050 2550);
DISPLAY INVISIBLE (3050 2550);
FORCEPROP 2 LAST CDS_SEC 1
J 0
(3050 2550);
PAINT MONO (3050 2550);
DISPLAY INVISIBLE (3050 2550);
FORCEPROP 1 LASTPIN (3200 2350) $PN 2
J 0
(3162 2362);
DISPLAY 0.787234 (3162 2362);
PAINT ORANGE (3162 2362);
DISPLAY INVISIBLE (3162 2362);
FORCEPROP 2 LAST CDS_LIB mstr_discrete
J 0
(3100 2350);
PAINT MONO (3100 2350);
DISPLAY INVISIBLE (3100 2350);
FORCEADD RES..1
(3075 2250);
FORCEPROP 1 LAST VALUE 33.2
J 2
(3050 2150);
DISPLAY 0.617021 (3050 2150);
PAINT SKYBLUE (3050 2150);
FORCEPROP 1 LAST WATTAGE 1/16W
J 2
(3050 2100);
DISPLAY 0.617021 (3050 2100);
PAINT SKYBLUE (3050 2100);
FORCEPROP 1 LAST PART_NUMBER G21796-074
J 0
(3025 2350);
DISPLAY 0.617021 (3025 2350);
PAINT BLUE (3025 2350);
FORCEPROP 1 LAST LOCATION R7B1
J 0
(3025 2300);
DISPLAY 0.617021 (3025 2300);
PAINT AQUA (3025 2300);
FORCEPROP 1 LAST MATERIAL CHIP
J 0
(3075 2100);
DISPLAY 0.617021 (3075 2100);
PAINT SKYBLUE (3075 2100);
FORCEPROP 1 LAST TOLERANCE 1%
J 0
(3075 2150);
DISPLAY 0.617021 (3075 2150);
PAINT SKYBLUE (3075 2150);
FORCEPROP 1 LAST PACK_TYPE 0402
J 0
(3325 2100);
DISPLAY 0.617021 (3325 2100);
PAINT SKYBLUE (3325 2100);
FORCEPROP 1 LASTPIN (2975 2250) $PN 1
J 0
(2987 2262);
DISPLAY 0.787234 (2987 2262);
PAINT ORANGE (2987 2262);
DISPLAY INVISIBLE (2987 2262);
FORCEPROP 2 LAST CDS_LOCATION R7B1
J 0
(3025 2300);
DISPLAY 0.617021 (3025 2300);
PAINT AQUA (3025 2300);
DISPLAY INVISIBLE (3025 2300);
FORCEPROP 2 LAST CDS_SEC 1
J 0
(3025 2450);
PAINT MONO (3025 2450);
DISPLAY INVISIBLE (3025 2450);
FORCEPROP 2 LAST $SEC 1
J 0
(3025 2450);
PAINT MONO (3025 2450);
DISPLAY INVISIBLE (3025 2450);
FORCEPROP 1 LAST PATH I12
J 0
(3025 2400);
DISPLAY 0.978723 (3025 2400);
PAINT WHITE (3025 2400);
DISPLAY INVISIBLE (3025 2400);
FORCEPROP 2 LAST CDS_LIB mstr_discrete
J 0
(3075 2250);
PAINT MONO (3075 2250);
DISPLAY INVISIBLE (3075 2250);
FORCEPROP 1 LASTPIN (3175 2250) $PN 2
J 0
(3137 2262);
DISPLAY 0.787234 (3137 2262);
PAINT ORANGE (3137 2262);
DISPLAY INVISIBLE (3137 2262);
FORCEADD P3V3_STBY..1
(2550 3575);
FORCEPROP 3 LASTPIN (2550 3525) SIG_NAME P3V3_STBY\g
J 0
(2560 3535);
DISPLAY 0.659574 (2560 3535);
PAINT MONO (2560 3535);
DISPLAY INVISIBLE (2560 3535);
FORCEPROP 1 LAST HDL_POWER P3V3_STBY
J 0
(2250 3450);
DISPLAY 0.872340 (2250 3450);
PAINT ORANGE (2250 3450);
DISPLAY INVISIBLE (2250 3450);
FORCEPROP 1 LAST BODY_TYPE PLUMBING
J 0
(2505 3532);
DISPLAY 0.340426 (2505 3532);
PAINT GREEN (2505 3532);
DISPLAY INVISIBLE (2505 3532);
FORCEPROP 1 LAST VOLTAGE 3.3V
J 0
(2505 3532);
DISPLAY 0.340426 (2505 3532);
PAINT SKYBLUE (2505 3532);
DISPLAY INVISIBLE (2505 3532);
FORCEPROP 2 LAST CDS_LIB mstr_symbols
J 0
(2550 3575);
PAINT ORANGE (2550 3575);
DISPLAY INVISIBLE (2550 3575);
FORCEPROP 1 LAST PATH I13
J 0
(2595 3577);
DISPLAY 0.340426 (2595 3577);
PAINT GREEN (2595 3577);
DISPLAY INVISIBLE (2595 3577);
FORCEPROP 1 LAST SIZE 1B
J 0
(2595 3597);
DISPLAY 0.340426 (2595 3597);
PAINT GREEN (2595 3597);
DISPLAY INVISIBLE (2595 3597);
FORCEADD RES..2
(2650 2725);
FORCEPROP 1 LAST PACK_TYPE 0402
J 0
(2690 2550);
DISPLAY 0.617021 (2690 2550);
PAINT SKYBLUE (2690 2550);
FORCEPROP 1 LASTPIN (2650 2625) $PN 2
J 0
(2655 2635);
DISPLAY 0.617021 (2655 2635);
PAINT ORANGE (2655 2635);
FORCEPROP 1 LASTPIN (2650 2825) $PN 1
J 0
(2655 2787);
DISPLAY 0.617021 (2655 2787);
PAINT ORANGE (2655 2787);
FORCEPROP 1 LAST TOLERANCE 1.0%
J 0
(2695 2750);
DISPLAY 0.617021 (2695 2750);
PAINT SKYBLUE (2695 2750);
FORCEPROP 1 LAST LOCATION R7A9
J 0
(2695 2850);
DISPLAY 0.617021 (2695 2850);
PAINT AQUA (2695 2850);
FORCEPROP 1 LAST WATTAGE 1/16W
J 0
(2690 2700);
DISPLAY 0.617021 (2690 2700);
PAINT SKYBLUE (2690 2700);
FORCEPROP 1 LAST VALUE 2.26K
J 0
(2695 2800);
DISPLAY 0.617021 (2695 2800);
PAINT SKYBLUE (2695 2800);
FORCEPROP 1 LAST PART_NUMBER G21796-311
J 0
(2690 2600);
DISPLAY 0.617021 (2690 2600);
PAINT BLUE (2690 2600);
FORCEPROP 1 LAST MATERIAL EMPTY
J 0
(2690 2650);
DISPLAY 0.617021 (2690 2650);
PAINT RED (2690 2650);
FORCEPROP 2 LAST CDS_LIB mstr_discrete
J 0
(2650 2725);
PAINT ORANGE (2650 2725);
DISPLAY INVISIBLE (2650 2725);
FORCEPROP 2 LAST ROOM VDDQ_DEF_PWR_VR
J 0
(2700 2700);
DISPLAY 1.361702 (2700 2700);
PAINT ORANGE (2700 2700);
DISPLAY INVISIBLE (2700 2700);
FORCEPROP 1 LAST PATH I14
J 0
(2700 2900);
DISPLAY 0.978723 (2700 2900);
PAINT WHITE (2700 2900);
DISPLAY INVISIBLE (2700 2900);
FORCEPROP 2 LAST CDS_LOCATION R7A9
J 0
(2695 2850);
DISPLAY 0.617021 (2695 2850);
PAINT AQUA (2695 2850);
DISPLAY INVISIBLE (2695 2850);
FORCEPROP 2 LAST SEC 1
J 0
(2700 2975);
DISPLAY 0.680851 (2700 2975);
PAINT MONO (2700 2975);
DISPLAY INVISIBLE (2700 2975);
FORCEPROP 2 LAST SEC_TYPE 0402
J 0
(2700 2975);
DISPLAY 1.021277 (2700 2975);
PAINT ORANGE (2700 2975);
DISPLAY INVISIBLE (2700 2975);
FORCEADD RES..1
(2525 2200);
FORCEPROP 1 LAST WATTAGE 1/16W
J 2
(2425 2150);
DISPLAY 0.617021 (2425 2150);
PAINT SKYBLUE (2425 2150);
FORCEPROP 1 LAST VALUE 0.0
J 2
(2500 2150);
DISPLAY 0.617021 (2500 2150);
PAINT SKYBLUE (2500 2150);
FORCEPROP 1 LASTPIN (2425 2200) $PN 1
J 0
(2437 2212);
DISPLAY 0.617021 (2437 2212);
PAINT ORANGE (2437 2212);
FORCEPROP 1 LAST TOLERANCE 5%
J 0
(2525 2150);
DISPLAY 0.617021 (2525 2150);
PAINT SKYBLUE (2525 2150);
FORCEPROP 1 LAST PART_NUMBER G21497-005
J 0
(2375 2100);
DISPLAY 0.617021 (2375 2100);
PAINT BLUE (2375 2100);
FORCEPROP 1 LAST LOCATION R7A11
J 0
(2525 2250);
DISPLAY 0.617021 (2525 2250);
PAINT AQUA (2525 2250);
FORCEPROP 1 LAST PACK_TYPE 0402
J 0
(2625 2150);
DISPLAY 0.617021 (2625 2150);
PAINT SKYBLUE (2625 2150);
FORCEPROP 1 LASTPIN (2625 2200) $PN 2
J 0
(2587 2212);
DISPLAY 0.617021 (2587 2212);
PAINT ORANGE (2587 2212);
FORCEPROP 1 LAST MATERIAL CHIP
J 0
(2750 2150);
DISPLAY 0.617021 (2750 2150);
PAINT SKYBLUE (2750 2150);
FORCEPROP 2 LAST CDS_LIB mstr_discrete
J 0
(2525 2200);
PAINT ORANGE (2525 2200);
DISPLAY INVISIBLE (2525 2200);
FORCEPROP 2 LAST CDS_LOCATION R7A11
J 0
(2525 2250);
DISPLAY 0.617021 (2525 2250);
PAINT AQUA (2525 2250);
DISPLAY INVISIBLE (2525 2250);
FORCEPROP 2 LAST ROOM VDDQ_DEF_PWR_VR
J 0
(2475 2300);
DISPLAY 1.361702 (2475 2300);
PAINT ORANGE (2475 2300);
DISPLAY INVISIBLE (2475 2300);
FORCEPROP 1 LAST PATH I15
J 0
(2475 2350);
DISPLAY 0.978723 (2475 2350);
PAINT WHITE (2475 2350);
DISPLAY INVISIBLE (2475 2350);
FORCEPROP 2 LAST SEC_TYPE 0402
J 0
(2475 2425);
DISPLAY 1.021277 (2475 2425);
PAINT ORANGE (2475 2425);
DISPLAY INVISIBLE (2475 2425);
FORCEPROP 2 LAST SEC 1
J 0
(2475 2425);
DISPLAY 0.680851 (2475 2425);
PAINT MONO (2475 2425);
DISPLAY INVISIBLE (2475 2425);
FORCEADD RES..2
(2350 2900);
FORCEPROP 1 LAST PACK_TYPE 0402
J 0
(2390 2725);
DISPLAY 0.617021 (2390 2725);
PAINT SKYBLUE (2390 2725);
FORCEPROP 1 LASTPIN (2350 2800) $PN 2
J 0
(2355 2810);
DISPLAY 0.617021 (2355 2810);
PAINT ORANGE (2355 2810);
FORCEPROP 1 LASTPIN (2350 3000) $PN 1
J 0
(2355 2962);
DISPLAY 0.617021 (2355 2962);
PAINT ORANGE (2355 2962);
FORCEPROP 1 LAST LOCATION R7B5
J 0
(2395 3025);
DISPLAY 0.617021 (2395 3025);
PAINT AQUA (2395 3025);
FORCEPROP 1 LAST VALUE 1.00K
J 0
(2395 2975);
DISPLAY 0.617021 (2395 2975);
PAINT SKYBLUE (2395 2975);
FORCEPROP 1 LAST TOLERANCE 1%
J 0
(2395 2925);
DISPLAY 0.617021 (2395 2925);
PAINT SKYBLUE (2395 2925);
FORCEPROP 1 LAST MATERIAL CHIP
J 0
(2390 2825);
DISPLAY 0.617021 (2390 2825);
PAINT SKYBLUE (2390 2825);
FORCEPROP 1 LAST WATTAGE 1/16W
J 0
(2390 2875);
DISPLAY 0.617021 (2390 2875);
PAINT SKYBLUE (2390 2875);
FORCEPROP 1 LAST PART_NUMBER G21796-026
J 0
(2390 2775);
DISPLAY 0.617021 (2390 2775);
PAINT BLUE (2390 2775);
FORCEPROP 2 LAST CDS_LOCATION R7B5
J 0
(2395 3025);
DISPLAY 0.617021 (2395 3025);
PAINT AQUA (2395 3025);
DISPLAY INVISIBLE (2395 3025);
FORCEPROP 2 LAST CDS_LIB mstr_discrete
J 2
(2350 2900);
PAINT ORANGE (2350 2900);
DISPLAY INVISIBLE (2350 2900);
FORCEPROP 2 LAST ROOM VDDQ_DEF_PWR_VR
J 0
(2400 3075);
DISPLAY 1.361702 (2400 3075);
PAINT ORANGE (2400 3075);
DISPLAY INVISIBLE (2400 3075);
FORCEPROP 1 LAST PATH I16
J 0
(2400 3075);
DISPLAY 0.978723 (2400 3075);
PAINT WHITE (2400 3075);
DISPLAY INVISIBLE (2400 3075);
FORCEPROP 2 LAST SEC 1
J 0
(2400 3150);
DISPLAY 0.680851 (2400 3150);
PAINT MONO (2400 3150);
DISPLAY INVISIBLE (2400 3150);
FORCEPROP 2 LAST SEC_TYPE 0402
J 0
(2400 3150);
DISPLAY 1.021277 (2400 3150);
PAINT ORANGE (2400 3150);
DISPLAY INVISIBLE (2400 3150);
FORCEADD RES..2
(2150 2900);
FORCEPROP 1 LAST PART_NUMBER G21796-026
J 0
(1840 2750);
DISPLAY 0.617021 (1840 2750);
PAINT BLUE (1840 2750);
FORCEPROP 1 LASTPIN (2150 2800) $PN 2
J 0
(2155 2810);
DISPLAY 0.617021 (2155 2810);
PAINT ORANGE (2155 2810);
FORCEPROP 1 LAST TOLERANCE 1%
J 0
(2195 2925);
DISPLAY 0.617021 (2195 2925);
PAINT SKYBLUE (2195 2925);
FORCEPROP 1 LASTPIN (2150 3000) $PN 1
J 0
(2155 2962);
DISPLAY 0.617021 (2155 2962);
PAINT ORANGE (2155 2962);
FORCEPROP 1 LAST WATTAGE 1/16W
J 0
(2190 2875);
DISPLAY 0.617021 (2190 2875);
PAINT SKYBLUE (2190 2875);
FORCEPROP 1 LAST MATERIAL CHIP
J 0
(2190 2825);
DISPLAY 0.617021 (2190 2825);
PAINT SKYBLUE (2190 2825);
FORCEPROP 1 LAST PACK_TYPE 0402
J 0
(2190 2725);
DISPLAY 0.617021 (2190 2725);
PAINT SKYBLUE (2190 2725);
FORCEPROP 1 LAST VALUE 1.00K
J 0
(2195 2975);
DISPLAY 0.617021 (2195 2975);
PAINT SKYBLUE (2195 2975);
FORCEPROP 1 LAST LOCATION R7B4
J 0
(2195 3025);
DISPLAY 0.617021 (2195 3025);
PAINT AQUA (2195 3025);
FORCEPROP 2 LAST CDS_LIB mstr_discrete
J 0
(2150 2900);
PAINT ORANGE (2150 2900);
DISPLAY INVISIBLE (2150 2900);
FORCEPROP 2 LAST CDS_LOCATION R7B4
J 0
(2195 3025);
DISPLAY 0.617021 (2195 3025);
PAINT AQUA (2195 3025);
DISPLAY INVISIBLE (2195 3025);
FORCEPROP 2 LAST SEC_TYPE 0402
J 0
(2200 3125);
DISPLAY 1.021277 (2200 3125);
PAINT ORANGE (2200 3125);
DISPLAY INVISIBLE (2200 3125);
FORCEPROP 2 LAST SEC 1
J 0
(2200 3125);
DISPLAY 0.680851 (2200 3125);
PAINT MONO (2200 3125);
DISPLAY INVISIBLE (2200 3125);
FORCEPROP 1 LAST PATH I17
J 0
(2200 3075);
DISPLAY 0.978723 (2200 3075);
PAINT WHITE (2200 3075);
DISPLAY INVISIBLE (2200 3075);
FORCEPROP 0 LAST ROOM VDDQ_DEF_PWR_VR
J 0
(2200 3125);
DISPLAY 1.021277 (2200 3125);
PAINT ORANGE (2200 3125);
DISPLAY INVISIBLE (2200 3125);
FORCEADD OFFPAGE..1
R 2
(3925 1850);
FORCEPROP 2 LAST $XR0 138 
J 0
(4111 1850);
DISPLAY 0.638298 (4111 1850);
PAINT MONO (4111 1850);
FORCEPROP 2 LAST $XR1 159 
J 0
(4231 1850);
DISPLAY 0.638298 (4231 1850);
PAINT MONO (4231 1850);
FORCEPROP 2 LAST $XR2 211 
J 0
(4351 1850);
DISPLAY 0.638298 (4351 1850);
PAINT MONO (4351 1850);
FORCEPROP 2 LAST $XR3 213 
J 0
(4471 1850);
DISPLAY 0.638298 (4471 1850);
PAINT MONO (4471 1850);
FORCEPROP 2 LAST $XR4 235 
J 0
(4591 1850);
DISPLAY 0.638298 (4591 1850);
PAINT MONO (4591 1850);
FORCEPROP 2 LAST $XR5 193 
J 0
(4711 1850);
DISPLAY 0.638298 (4711 1850);
PAINT MONO (4711 1850);
FORCEPROP 2 LAST $XR6 194 
J 0
(4831 1850);
DISPLAY 0.638298 (4831 1850);
PAINT MONO (4831 1850);
FORCEPROP 2 LAST $XR7 201 
J 0
(4951 1850);
DISPLAY 0.638298 (4951 1850);
PAINT MONO (4951 1850);
FORCEPROP 2 LAST $XR8 206 
J 0
(5071 1850);
DISPLAY 0.638298 (5071 1850);
PAINT MONO (5071 1850);
FORCEPROP 2 LAST $XR9 215 
J 0
(4231 1814);
DISPLAY 0.638298 (4231 1814);
PAINT MONO (4231 1814);
FORCEPROP 2 LAST $XR10 223 
J 0
(4351 1814);
DISPLAY 0.638298 (4351 1814);
PAINT MONO (4351 1814);
FORCEPROP 2 LAST $XR11 226 
J 0
(4471 1814);
DISPLAY 0.638298 (4471 1814);
PAINT MONO (4471 1814);
FORCEPROP 2 LAST ROOM VDDQ_DEF_PWR_VR
J 0
(3500 1925);
DISPLAY 1.361702 (3500 1925);
PAINT ORANGE (3500 1925);
DISPLAY INVISIBLE (3500 1925);
FORCEPROP 1 LAST COMMENT_BODY TRUE
J 2
(3800 1750);
DISPLAY 1.170213 (3800 1750);
PAINT GREEN (3800 1750);
DISPLAY INVISIBLE (3800 1750);
FORCEPROP 1 LAST OFFPAGE TRUE
J 2
(3600 1725);
DISPLAY 1.170213 (3600 1725);
PAINT GREEN (3600 1725);
DISPLAY INVISIBLE (3600 1725);
FORCEPROP 2 LAST CDS_LIB mstr_standard
J 0
(3925 1850);
PAINT ORANGE (3925 1850);
DISPLAY INVISIBLE (3925 1850);
FORCEPROP 2 LAST PATH I18
J 0
(5075 1900);
DISPLAY 1.021277 (5075 1900);
PAINT ORANGE (5075 1900);
DISPLAY INVISIBLE (5075 1900);
FORCEADD OFFPAGE..3
(3925 1800);
FORCEPROP 2 LAST $XR0 138 
J 0
(4139 1800);
DISPLAY 0.638298 (4139 1800);
PAINT MONO (4139 1800);
FORCEPROP 2 LAST $XR1 159 
J 0
(4139 1764);
DISPLAY 0.638298 (4139 1764);
PAINT MONO (4139 1764);
FORCEPROP 2 LAST $XR2 193 
J 0
(4259 1764);
DISPLAY 0.638298 (4259 1764);
PAINT MONO (4259 1764);
FORCEPROP 2 LAST $XR3 194 
J 0
(4379 1764);
DISPLAY 0.638298 (4379 1764);
PAINT MONO (4379 1764);
FORCEPROP 2 LAST $XR4 201 
J 0
(4499 1764);
DISPLAY 0.638298 (4499 1764);
PAINT MONO (4499 1764);
FORCEPROP 2 LAST $XR5 206 
J 0
(4619 1764);
DISPLAY 0.638298 (4619 1764);
PAINT MONO (4619 1764);
FORCEPROP 2 LAST $XR6 211 
J 0
(4739 1764);
DISPLAY 0.638298 (4739 1764);
PAINT MONO (4739 1764);
FORCEPROP 2 LAST $XR7 213 
J 0
(4859 1764);
DISPLAY 0.638298 (4859 1764);
PAINT MONO (4859 1764);
FORCEPROP 2 LAST $XR8 215 
J 0
(4979 1764);
DISPLAY 0.638298 (4979 1764);
PAINT MONO (4979 1764);
FORCEPROP 2 LAST $XR9 223 
J 0
(5099 1764);
DISPLAY 0.638298 (5099 1764);
PAINT MONO (5099 1764);
FORCEPROP 2 LAST $XR10 226 
J 0
(4619 1800);
DISPLAY 0.638298 (4619 1800);
PAINT MONO (4619 1800);
FORCEPROP 2 LAST $XR11 235 
J 0
(4739 1800);
DISPLAY 0.638298 (4739 1800);
PAINT MONO (4739 1800);
FORCEPROP 2 LAST ROOM VDDQ_DEF_PWR_VR
J 0
(3525 1875);
DISPLAY 1.361702 (3525 1875);
PAINT ORANGE (3525 1875);
DISPLAY INVISIBLE (3525 1875);
FORCEPROP 1 LAST COMMENT_BODY TRUE
J 0
(3875 1700);
DISPLAY 1.170213 (3875 1700);
PAINT GREEN (3875 1700);
DISPLAY INVISIBLE (3875 1700);
FORCEPROP 2 LAST CDS_LIB mstr_standard
J 0
(3925 1800);
PAINT ORANGE (3925 1800);
DISPLAY INVISIBLE (3925 1800);
FORCEPROP 1 LAST OFFPAGE TRUE
J 0
(4250 1675);
DISPLAY 1.170213 (4250 1675);
PAINT GREEN (4250 1675);
DISPLAY INVISIBLE (4250 1675);
FORCEPROP 2 LAST PATH I19
J 0
(4875 1850);
DISPLAY 1.021277 (4875 1850);
PAINT ORANGE (4875 1850);
DISPLAY INVISIBLE (4875 1850);
FORCEADD OFFPAGE..2
(3950 1300);
FORCEPROP 2 LAST $XR0 219 
J 0
(4139 1300);
DISPLAY 0.638298 (4139 1300);
PAINT MONO (4139 1300);
FORCEPROP 2 LAST ROOM VDDQ_DEF_PWR_VR
J 0
(3525 1375);
DISPLAY 1.361702 (3525 1375);
PAINT ORANGE (3525 1375);
DISPLAY INVISIBLE (3525 1375);
FORCEPROP 1 LAST COMMENT_BODY TRUE
J 0
(3905 1205);
DISPLAY 1.170213 (3905 1205);
PAINT GREEN (3905 1205);
DISPLAY INVISIBLE (3905 1205);
FORCEPROP 2 LAST CDS_LIB mstr_standard
J 0
(3950 1300);
PAINT ORANGE (3950 1300);
DISPLAY INVISIBLE (3950 1300);
FORCEPROP 2 LAST PATH I2
J 0
(4150 1350);
DISPLAY 1.021277 (4150 1350);
PAINT ORANGE (4150 1350);
DISPLAY INVISIBLE (4150 1350);
FORCEPROP 1 LAST OFFPAGE TRUE
J 0
(4275 1175);
DISPLAY 1.170213 (4275 1175);
PAINT GREEN (4275 1175);
DISPLAY INVISIBLE (4275 1175);
FORCEADD OFFPAGE..3
(3925 1500);
FORCEPROP 2 LAST $XR0 21 
J 0
(4139 1500);
DISPLAY 0.638298 (4139 1500);
PAINT MONO (4139 1500);
FORCEPROP 2 LAST $XR1 194 
J 0
(4229 1500);
DISPLAY 0.638298 (4229 1500);
PAINT MONO (4229 1500);
FORCEPROP 2 LAST $XR2 215 
J 0
(4349 1500);
DISPLAY 0.638298 (4349 1500);
PAINT MONO (4349 1500);
FORCEPROP 2 LAST ROOM VDDQ_DEF_PWR_VR
J 0
(3525 1575);
DISPLAY 1.361702 (3525 1575);
PAINT ORANGE (3525 1575);
DISPLAY INVISIBLE (3525 1575);
FORCEPROP 1 LAST COMMENT_BODY TRUE
J 0
(3875 1400);
DISPLAY 1.170213 (3875 1400);
PAINT GREEN (3875 1400);
DISPLAY INVISIBLE (3875 1400);
FORCEPROP 2 LAST CDS_LIB mstr_standard
J 0
(3925 1500);
PAINT ORANGE (3925 1500);
DISPLAY INVISIBLE (3925 1500);
FORCEPROP 1 LAST OFFPAGE TRUE
J 0
(4250 1375);
DISPLAY 1.170213 (4250 1375);
PAINT GREEN (4250 1375);
DISPLAY INVISIBLE (4250 1375);
FORCEPROP 2 LAST PATH I20
J 0
(4250 1550);
DISPLAY 1.021277 (4250 1550);
PAINT ORANGE (4250 1550);
DISPLAY INVISIBLE (4250 1550);
FORCEADD RES..1
(3000 1850);
FORCEPROP 1 LAST WATTAGE 1/16W
J 2
(2975 1700);
DISPLAY 0.617021 (2975 1700);
PAINT SKYBLUE (2975 1700);
FORCEPROP 1 LAST TOLERANCE 1%
J 0
(3000 1750);
DISPLAY 0.617021 (3000 1750);
PAINT SKYBLUE (3000 1750);
FORCEPROP 1 LAST VALUE 20.0
J 2
(2975 1750);
DISPLAY 0.617021 (2975 1750);
PAINT SKYBLUE (2975 1750);
FORCEPROP 1 LAST LOCATION R7B3
J 0
(2950 1900);
DISPLAY 0.617021 (2950 1900);
PAINT AQUA (2950 1900);
FORCEPROP 1 LAST MATERIAL CHIP
J 0
(3000 1700);
DISPLAY 0.617021 (3000 1700);
PAINT SKYBLUE (3000 1700);
FORCEPROP 1 LAST PACK_TYPE 0402
J 0
(3000 1650);
DISPLAY 0.617021 (3000 1650);
PAINT SKYBLUE (3000 1650);
FORCEPROP 1 LAST PART_NUMBER G21796-173
J 0
(2950 1950);
DISPLAY 0.617021 (2950 1950);
PAINT BLUE (2950 1950);
FORCEPROP 1 LASTPIN (2900 1850) $PN 1
J 0
(2912 1862);
DISPLAY 0.787234 (2912 1862);
PAINT ORANGE (2912 1862);
DISPLAY INVISIBLE (2912 1862);
FORCEPROP 1 LASTPIN (3100 1850) $PN 2
J 0
(3062 1862);
DISPLAY 0.787234 (3062 1862);
PAINT ORANGE (3062 1862);
DISPLAY INVISIBLE (3062 1862);
FORCEPROP 2 LAST ROOM VDDQ_DEF_PWR_VR
J 0
(2950 1950);
DISPLAY 1.361702 (2950 1950);
PAINT ORANGE (2950 1950);
DISPLAY INVISIBLE (2950 1950);
FORCEPROP 2 LAST CDS_LIB mstr_discrete
J 0
(3000 1850);
PAINT ORANGE (3000 1850);
DISPLAY INVISIBLE (3000 1850);
FORCEPROP 1 LAST PATH I21
J 0
(2950 2000);
DISPLAY 0.978723 (2950 2000);
PAINT WHITE (2950 2000);
DISPLAY INVISIBLE (2950 2000);
FORCEPROP 2 LAST CDS_LOCATION R7B3
J 0
(2950 1900);
DISPLAY 0.617021 (2950 1900);
PAINT AQUA (2950 1900);
DISPLAY INVISIBLE (2950 1900);
FORCEPROP 2 LAST $SEC 1
J 0
(2950 2050);
PAINT MONO (2950 2050);
DISPLAY INVISIBLE (2950 2050);
FORCEPROP 2 LAST CDS_SEC 1
J 0
(2950 2050);
PAINT MONO (2950 2050);
DISPLAY INVISIBLE (2950 2050);
FORCEADD CAP_A..1
(3525 0);
FORCEPROP 1 LASTPIN (3525 -100) $PN 2
J 0
(3535 -120);
DISPLAY 0.617021 (3535 -120);
PAINT ORANGE (3535 -120);
FORCEPROP 1 LAST MATERIAL X6S
J 0
(3575 -100);
DISPLAY 0.617021 (3575 -100);
PAINT SKYBLUE (3575 -100);
FORCEPROP 1 LAST PACK_TYPE 0402V
J 0
(3575 -200);
DISPLAY 0.617021 (3575 -200);
PAINT SKYBLUE (3575 -200);
FORCEPROP 1 LAST TOLERANCE 10%
J 0
(3575 -50);
DISPLAY 0.617021 (3575 -50);
PAINT SKYBLUE (3575 -50);
FORCEPROP 1 LAST PART_NUMBER D97712-004
J 0
(3575 -150);
DISPLAY 0.617021 (3575 -150);
PAINT BLUE (3575 -150);
FORCEPROP 1 LAST VOLTAGE 6.3V
J 0
(3575 0);
DISPLAY 0.617021 (3575 0);
PAINT SKYBLUE (3575 0);
FORCEPROP 1 LASTPIN (3525 100) $PN 1
J 0
(3535 80);
DISPLAY 0.617021 (3535 80);
PAINT ORANGE (3535 80);
FORCEPROP 1 LAST VALUE 1.0UF
J 0
(3575 50);
DISPLAY 0.617021 (3575 50);
PAINT SKYBLUE (3575 50);
FORCEPROP 1 LAST LOCATION C7B1
J 0
(3575 100);
DISPLAY 0.617021 (3575 100);
PAINT AQUA (3575 100);
FORCEPROP 2 LAST CDS_LIB dev_discrete
J 0
(3525 0);
PAINT ORANGE (3525 0);
DISPLAY INVISIBLE (3525 0);
FORCEPROP 2 LAST CDS_LOCATION C7B1
J 0
(3575 100);
DISPLAY 0.617021 (3575 100);
PAINT AQUA (3575 100);
DISPLAY INVISIBLE (3575 100);
FORCEPROP 2 LAST CDS_SEC 1
J 0
(3575 150);
PAINT ORANGE (3575 150);
DISPLAY INVISIBLE (3575 150);
FORCEPROP 2 LAST SEC_TYPE 0402V
J 0
(3575 200);
DISPLAY 1.021277 (3575 200);
PAINT ORANGE (3575 200);
DISPLAY INVISIBLE (3575 200);
FORCEPROP 2 LAST SEC 1
J 0
(3575 200);
DISPLAY 0.680851 (3575 200);
PAINT MONO (3575 200);
DISPLAY INVISIBLE (3575 200);
FORCEPROP 1 LAST PATH I22
J 0
(3575 150);
DISPLAY 0.978723 (3575 150);
PAINT WHITE (3575 150);
DISPLAY INVISIBLE (3575 150);
FORCEPROP 2 LAST ROOM VDDQ_DEF_PWR_VR
J 0
(3575 150);
DISPLAY 1.361702 (3575 150);
PAINT ORANGE (3575 150);
DISPLAY INVISIBLE (3575 150);
FORCEADD CAP_A..1
(3125 0);
FORCEPROP 1 LASTPIN (3125 -100) $PN 2
J 0
(3135 -120);
DISPLAY 0.617021 (3135 -120);
PAINT ORANGE (3135 -120);
FORCEPROP 1 LAST MATERIAL X7R
J 0
(3175 -100);
DISPLAY 0.617021 (3175 -100);
PAINT SKYBLUE (3175 -100);
FORCEPROP 1 LAST PACK_TYPE 0402V
J 0
(3175 -200);
DISPLAY 0.617021 (3175 -200);
PAINT SKYBLUE (3175 -200);
FORCEPROP 1 LAST TOLERANCE 10%
J 0
(3175 -50);
DISPLAY 0.617021 (3175 -50);
PAINT SKYBLUE (3175 -50);
FORCEPROP 1 LAST PART_NUMBER A36096-030
J 0
(3175 -150);
DISPLAY 0.617021 (3175 -150);
PAINT BLUE (3175 -150);
FORCEPROP 1 LAST VOLTAGE 16V
J 0
(3175 0);
DISPLAY 0.617021 (3175 0);
PAINT SKYBLUE (3175 0);
FORCEPROP 1 LAST LOCATION C7B2
J 0
(3175 100);
DISPLAY 0.617021 (3175 100);
PAINT AQUA (3175 100);
FORCEPROP 1 LASTPIN (3125 100) $PN 1
J 0
(3135 80);
DISPLAY 0.617021 (3135 80);
PAINT ORANGE (3135 80);
FORCEPROP 1 LAST VALUE 0.1UF
J 0
(3175 50);
DISPLAY 0.617021 (3175 50);
PAINT SKYBLUE (3175 50);
FORCEPROP 2 LAST CDS_LIB dev_discrete
J 0
(3125 0);
PAINT ORANGE (3125 0);
DISPLAY INVISIBLE (3125 0);
FORCEPROP 2 LAST SEC 1
J 0
(3175 225);
DISPLAY 0.680851 (3175 225);
PAINT MONO (3175 225);
DISPLAY INVISIBLE (3175 225);
FORCEPROP 2 LAST CDS_SEC 1
J 0
(3175 150);
PAINT ORANGE (3175 150);
DISPLAY INVISIBLE (3175 150);
FORCEPROP 2 LAST CDS_LOCATION C7B2
J 0
(3175 100);
DISPLAY 0.617021 (3175 100);
PAINT AQUA (3175 100);
DISPLAY INVISIBLE (3175 100);
FORCEPROP 2 LAST ROOM VDDQ_DEF_PWR_VR
J 0
(3175 150);
DISPLAY 1.361702 (3175 150);
PAINT ORANGE (3175 150);
DISPLAY INVISIBLE (3175 150);
FORCEPROP 1 LAST PATH I23
J 0
(3175 150);
DISPLAY 0.978723 (3175 150);
PAINT WHITE (3175 150);
DISPLAY INVISIBLE (3175 150);
FORCEPROP 2 LAST SEC_TYPE 0402V
J 0
(3175 225);
DISPLAY 1.021277 (3175 225);
PAINT ORANGE (3175 225);
DISPLAY INVISIBLE (3175 225);
FORCEADD RES..1
(2675 1800);
FORCEPROP 1 LAST WATTAGE 1/16W
J 2
(2675 1725);
DISPLAY 0.617021 (2675 1725);
PAINT SKYBLUE (2675 1725);
FORCEPROP 1 LAST VALUE 20.0
J 2
(2675 1750);
DISPLAY 0.617021 (2675 1750);
PAINT SKYBLUE (2675 1750);
FORCEPROP 1 LAST PACK_TYPE 0402
J 0
(2625 1700);
DISPLAY 0.617021 (2625 1700);
PAINT SKYBLUE (2625 1700);
FORCEPROP 1 LAST TOLERANCE 1%
J 0
(2725 1750);
DISPLAY 0.617021 (2725 1750);
PAINT SKYBLUE (2725 1750);
FORCEPROP 1 LAST LOCATION R7B2
J 0
(2625 1850);
DISPLAY 0.617021 (2625 1850);
PAINT AQUA (2625 1850);
FORCEPROP 1 LAST MATERIAL CHIP
J 0
(2700 1725);
DISPLAY 0.617021 (2700 1725);
PAINT SKYBLUE (2700 1725);
FORCEPROP 1 LAST PART_NUMBER G21796-173
J 0
(2625 1900);
DISPLAY 0.617021 (2625 1900);
PAINT BLUE (2625 1900);
FORCEPROP 2 LAST CDS_LIB mstr_discrete
J 0
(2675 1800);
PAINT ORANGE (2675 1800);
DISPLAY INVISIBLE (2675 1800);
FORCEPROP 2 LAST CDS_SEC 1
J 0
(2625 2000);
PAINT MONO (2625 2000);
DISPLAY INVISIBLE (2625 2000);
FORCEPROP 2 LAST $SEC 1
J 0
(2625 2000);
PAINT MONO (2625 2000);
DISPLAY INVISIBLE (2625 2000);
FORCEPROP 2 LAST CDS_LOCATION R7B2
J 0
(2625 1850);
DISPLAY 0.617021 (2625 1850);
PAINT AQUA (2625 1850);
DISPLAY INVISIBLE (2625 1850);
FORCEPROP 1 LAST PATH I24
J 0
(2625 1950);
DISPLAY 0.978723 (2625 1950);
PAINT WHITE (2625 1950);
DISPLAY INVISIBLE (2625 1950);
FORCEPROP 2 LAST ROOM VDDQ_DEF_PWR_VR
J 0
(2625 1900);
DISPLAY 1.361702 (2625 1900);
PAINT ORANGE (2625 1900);
DISPLAY INVISIBLE (2625 1900);
FORCEPROP 1 LASTPIN (2575 1800) $PN 1
J 0
(2587 1812);
DISPLAY 0.787234 (2587 1812);
PAINT ORANGE (2587 1812);
DISPLAY INVISIBLE (2587 1812);
FORCEPROP 1 LASTPIN (2775 1800) $PN 2
J 0
(2737 1812);
DISPLAY 0.787234 (2737 1812);
PAINT ORANGE (2737 1812);
DISPLAY INVISIBLE (2737 1812);
FORCEADD RES..1
(2675 1500);
FORCEPROP 1 LAST WATTAGE 1/16W
J 2
(2650 1350);
DISPLAY 0.617021 (2650 1350);
PAINT SKYBLUE (2650 1350);
FORCEPROP 1 LAST VALUE 0.0
J 2
(2575 1400);
DISPLAY 0.617021 (2575 1400);
PAINT SKYBLUE (2575 1400);
FORCEPROP 1 LAST PART_NUMBER G21497-005
J 0
(2525 1450);
DISPLAY 0.617021 (2525 1450);
PAINT BLUE (2525 1450);
FORCEPROP 1 LAST TOLERANCE 5%
J 0
(2625 1400);
DISPLAY 0.617021 (2625 1400);
PAINT SKYBLUE (2625 1400);
FORCEPROP 1 LAST MATERIAL CHIP
J 0
(2675 1350);
DISPLAY 0.617021 (2675 1350);
PAINT SKYBLUE (2675 1350);
FORCEPROP 1 LAST PACK_TYPE 0402
J 0
(2750 1400);
DISPLAY 0.617021 (2750 1400);
PAINT SKYBLUE (2750 1400);
FORCEPROP 1 LASTPIN (2575 1500) $PN 1
J 0
(2587 1512);
DISPLAY 0.617021 (2587 1512);
PAINT ORANGE (2587 1512);
FORCEPROP 1 LASTPIN (2775 1500) $PN 2
J 0
(2737 1512);
DISPLAY 0.617021 (2737 1512);
PAINT ORANGE (2737 1512);
FORCEPROP 1 LAST LOCATION R7A12
J 0
(2625 1550);
DISPLAY 0.617021 (2625 1550);
PAINT AQUA (2625 1550);
FORCEPROP 2 LAST CDS_LIB mstr_discrete
J 0
(2675 1500);
PAINT ORANGE (2675 1500);
DISPLAY INVISIBLE (2675 1500);
FORCEPROP 2 LAST SEC_TYPE 0402
J 0
(2625 1700);
DISPLAY 1.021277 (2625 1700);
PAINT ORANGE (2625 1700);
DISPLAY INVISIBLE (2625 1700);
FORCEPROP 2 LAST SEC 1
J 0
(2625 1700);
DISPLAY 0.680851 (2625 1700);
PAINT MONO (2625 1700);
DISPLAY INVISIBLE (2625 1700);
FORCEPROP 2 LAST CDS_LOCATION R7A12
J 0
(2625 1550);
DISPLAY 0.617021 (2625 1550);
PAINT AQUA (2625 1550);
DISPLAY INVISIBLE (2625 1550);
FORCEPROP 1 LAST PATH I25
J 0
(2625 1650);
DISPLAY 0.978723 (2625 1650);
PAINT WHITE (2625 1650);
DISPLAY INVISIBLE (2625 1650);
FORCEPROP 2 LAST ROOM VDDQ_DEF_PWR_VR
J 0
(2625 1600);
DISPLAY 1.361702 (2625 1600);
PAINT ORANGE (2625 1600);
DISPLAY INVISIBLE (2625 1600);
FORCEADD CAP..1
(2800 1025);
FORCEPROP 1 LASTPIN (2800 925) $PN 2
J 0
(2810 905);
DISPLAY 0.617021 (2810 905);
PAINT ORANGE (2810 905);
FORCEPROP 1 LAST MATERIAL X7R
J 0
(2850 925);
DISPLAY 0.617021 (2850 925);
PAINT SKYBLUE (2850 925);
FORCEPROP 1 LAST PACK_TYPE 0402LF
J 0
(2850 825);
DISPLAY 0.617021 (2850 825);
PAINT SKYBLUE (2850 825);
FORCEPROP 1 LAST TOLERANCE 10%
J 0
(2850 975);
DISPLAY 0.617021 (2850 975);
PAINT SKYBLUE (2850 975);
FORCEPROP 1 LASTPIN (2800 1125) $PN 1
J 0
(2810 1105);
DISPLAY 0.617021 (2810 1105);
PAINT ORANGE (2810 1105);
FORCEPROP 1 LAST VOLTAGE 50V
J 0
(2850 1025);
DISPLAY 0.617021 (2850 1025);
PAINT SKYBLUE (2850 1025);
FORCEPROP 1 LAST VALUE 1000PF
J 0
(2850 1075);
DISPLAY 0.617021 (2850 1075);
PAINT SKYBLUE (2850 1075);
FORCEPROP 1 LAST LOCATION C7B3
J 0
(2850 1125);
DISPLAY 0.617021 (2850 1125);
PAINT AQUA (2850 1125);
FORCEPROP 1 LAST PART_NUMBER A36096-046
J 0
(2850 875);
DISPLAY 0.617021 (2850 875);
PAINT BLUE (2850 875);
FORCEPROP 2 LAST CDS_LIB mstr_discrete
J 0
(2800 1025);
PAINT MONO (2800 1025);
DISPLAY INVISIBLE (2800 1025);
FORCEPROP 0 LAST ROOM VDDQ_DEF_PWR_VR
J 0
(2850 1225);
DISPLAY 1.021277 (2850 1225);
PAINT ORANGE (2850 1225);
DISPLAY INVISIBLE (2850 1225);
FORCEPROP 1 LAST PATH I26
J 0
(2850 1175);
DISPLAY 0.978723 (2850 1175);
PAINT WHITE (2850 1175);
DISPLAY INVISIBLE (2850 1175);
FORCEPROP 2 LAST CDS_LOCATION C7B3
J 0
(2850 1125);
DISPLAY 0.617021 (2850 1125);
PAINT AQUA (2850 1125);
DISPLAY INVISIBLE (2850 1125);
FORCEPROP 2 LAST SEC 1
J 0
(2850 1225);
DISPLAY 0.680851 (2850 1225);
PAINT MONO (2850 1225);
DISPLAY INVISIBLE (2850 1225);
FORCEPROP 2 LAST SEC_TYPE 0402LF
J 0
(2850 1225);
DISPLAY 1.021277 (2850 1225);
PAINT ORANGE (2850 1225);
DISPLAY INVISIBLE (2850 1225);
FORCEADD GND..1
(2800 800);
FORCEPROP 3 LASTPIN (2800 850) SIG_NAME GND\g
J 0
(2810 860);
DISPLAY 0.659574 (2810 860);
PAINT MONO (2810 860);
DISPLAY INVISIBLE (2810 860);
FORCEPROP 2 LAST ROOM VDDQ_DEF_PWR_VR
J 0
(2225 875);
DISPLAY 1.361702 (2225 875);
PAINT ORANGE (2225 875);
DISPLAY INVISIBLE (2225 875);
FORCEPROP 1 LAST HDL_POWER GND
J 0
(2800 950);
DISPLAY 1.170213 (2800 950);
PAINT GREEN (2800 950);
DISPLAY INVISIBLE (2800 950);
FORCEPROP 1 LAST VOLTAGE 0
J 0
(2800 800);
PAINT SKYBLUE (2800 800);
DISPLAY INVISIBLE (2800 800);
FORCEPROP 2 LAST CDS_LIB mstr_symbols
J 0
(2800 800);
PAINT MONO (2800 800);
DISPLAY INVISIBLE (2800 800);
FORCEPROP 1 LAST BODY_TYPE PLUMBING
J 0
(2755 757);
DISPLAY 0.340426 (2755 757);
PAINT GREEN (2755 757);
DISPLAY INVISIBLE (2755 757);
FORCEPROP 1 LAST PATH I27
J 0
(2875 800);
DISPLAY 0.872340 (2875 800);
PAINT AQUA (2875 800);
DISPLAY INVISIBLE (2875 800);
FORCEPROP 1 LAST SIZE 1B
J 0
(2875 750);
DISPLAY 1.170213 (2875 750);
PAINT AQUA (2875 750);
DISPLAY INVISIBLE (2875 750);
FORCEADD GND..1
(1900 625);
FORCEPROP 3 LASTPIN (1900 675) SIG_NAME GND\g
J 0
(1910 685);
DISPLAY 0.659574 (1910 685);
PAINT MONO (1910 685);
DISPLAY INVISIBLE (1910 685);
FORCEPROP 2 LAST ROOM VDDQ_DEF_PWR_VR
J 0
(1325 700);
DISPLAY 1.361702 (1325 700);
PAINT ORANGE (1325 700);
DISPLAY INVISIBLE (1325 700);
FORCEPROP 1 LAST VOLTAGE 0
J 0
(1900 625);
PAINT SKYBLUE (1900 625);
DISPLAY INVISIBLE (1900 625);
FORCEPROP 2 LAST CDS_LIB mstr_symbols
J 0
(1900 625);
PAINT ORANGE (1900 625);
DISPLAY INVISIBLE (1900 625);
FORCEPROP 1 LAST SIZE 1B
J 0
(1975 575);
DISPLAY 1.170213 (1975 575);
PAINT AQUA (1975 575);
DISPLAY INVISIBLE (1975 575);
FORCEPROP 1 LAST BODY_TYPE PLUMBING
J 0
(1855 582);
DISPLAY 0.340426 (1855 582);
PAINT GREEN (1855 582);
DISPLAY INVISIBLE (1855 582);
FORCEPROP 1 LAST PATH I28
J 0
(1975 625);
DISPLAY 0.872340 (1975 625);
PAINT AQUA (1975 625);
DISPLAY INVISIBLE (1975 625);
FORCEPROP 1 LAST HDL_POWER GND
J 0
(1900 775);
DISPLAY 1.170213 (1900 775);
PAINT GREEN (1900 775);
DISPLAY INVISIBLE (1900 775);
FORCEADD CAP_A..1
(1425 2900);
FORCEPROP 1 LASTPIN (1425 2800) $PN 2
J 0
(1435 2780);
DISPLAY 0.617021 (1435 2780);
PAINT ORANGE (1435 2780);
FORCEPROP 1 LASTPIN (1425 3000) $PN 1
J 0
(1435 2980);
DISPLAY 0.617021 (1435 2980);
PAINT ORANGE (1435 2980);
FORCEPROP 1 LAST MATERIAL X6S
J 0
(1475 2800);
DISPLAY 0.617021 (1475 2800);
PAINT SKYBLUE (1475 2800);
FORCEPROP 1 LAST VOLTAGE 6.3V
J 0
(1475 2900);
DISPLAY 0.617021 (1475 2900);
PAINT SKYBLUE (1475 2900);
FORCEPROP 1 LAST PACK_TYPE 0402V
J 0
(1475 2700);
DISPLAY 0.617021 (1475 2700);
PAINT SKYBLUE (1475 2700);
FORCEPROP 1 LAST TOLERANCE 10%
J 0
(1475 2850);
DISPLAY 0.617021 (1475 2850);
PAINT SKYBLUE (1475 2850);
FORCEPROP 1 LAST VALUE 1.0UF
J 0
(1475 2950);
DISPLAY 0.617021 (1475 2950);
PAINT SKYBLUE (1475 2950);
FORCEPROP 1 LAST PART_NUMBER D97712-004
J 0
(1475 2750);
DISPLAY 0.617021 (1475 2750);
PAINT BLUE (1475 2750);
FORCEPROP 1 LAST LOCATION C7A37
J 0
(1475 3000);
DISPLAY 0.617021 (1475 3000);
PAINT AQUA (1475 3000);
FORCEPROP 2 LAST CDS_LIB dev_discrete
J 0
(1425 2900);
PAINT ORANGE (1425 2900);
DISPLAY INVISIBLE (1425 2900);
FORCEPROP 2 LAST CDS_LOCATION C7A37
J 0
(1475 3000);
DISPLAY 0.617021 (1475 3000);
PAINT AQUA (1475 3000);
DISPLAY INVISIBLE (1475 3000);
FORCEPROP 2 LAST ROOM VDDQ_DEF_PWR_VR
J 0
(1475 3050);
DISPLAY 1.361702 (1475 3050);
PAINT ORANGE (1475 3050);
DISPLAY INVISIBLE (1475 3050);
FORCEPROP 1 LAST PATH I29
J 0
(1475 3050);
DISPLAY 0.978723 (1475 3050);
PAINT WHITE (1475 3050);
DISPLAY INVISIBLE (1475 3050);
FORCEPROP 2 LAST CDS_SEC 1
J 0
(1475 3050);
PAINT ORANGE (1475 3050);
DISPLAY INVISIBLE (1475 3050);
FORCEPROP 2 LAST SEC_TYPE 0402V
J 0
(1475 3100);
DISPLAY 1.021277 (1475 3100);
PAINT ORANGE (1475 3100);
DISPLAY INVISIBLE (1475 3100);
FORCEPROP 2 LAST SEC 1
J 0
(1475 3100);
DISPLAY 0.680851 (1475 3100);
PAINT MONO (1475 3100);
DISPLAY INVISIBLE (1475 3100);
FORCEADD OFFPAGE..2
(3950 1250);
FORCEPROP 2 LAST $XR0 219 
J 0
(4139 1250);
DISPLAY 0.638298 (4139 1250);
PAINT MONO (4139 1250);
FORCEPROP 2 LAST ROOM VDDQ_DEF_PWR_VR
J 0
(3525 1325);
DISPLAY 1.361702 (3525 1325);
PAINT ORANGE (3525 1325);
DISPLAY INVISIBLE (3525 1325);
FORCEPROP 1 LAST COMMENT_BODY TRUE
J 0
(3905 1155);
DISPLAY 1.170213 (3905 1155);
PAINT GREEN (3905 1155);
DISPLAY INVISIBLE (3905 1155);
FORCEPROP 2 LAST CDS_LIB mstr_standard
J 0
(3950 1250);
PAINT ORANGE (3950 1250);
DISPLAY INVISIBLE (3950 1250);
FORCEPROP 2 LAST PATH I3
J 0
(4150 1300);
DISPLAY 1.021277 (4150 1300);
PAINT ORANGE (4150 1300);
DISPLAY INVISIBLE (4150 1300);
FORCEPROP 1 LAST OFFPAGE TRUE
J 0
(4275 1125);
DISPLAY 1.170213 (4275 1125);
PAINT GREEN (4275 1125);
DISPLAY INVISIBLE (4275 1125);
FORCEADD GND..1
(1425 2700);
FORCEPROP 3 LASTPIN (1425 2750) SIG_NAME GND\g
J 0
(1435 2760);
DISPLAY 0.659574 (1435 2760);
PAINT MONO (1435 2760);
DISPLAY INVISIBLE (1435 2760);
FORCEPROP 2 LAST ROOM VDDQ_DEF_PWR_VR
J 0
(850 2775);
DISPLAY 1.361702 (850 2775);
PAINT ORANGE (850 2775);
DISPLAY INVISIBLE (850 2775);
FORCEPROP 1 LAST BODY_TYPE PLUMBING
J 0
(1380 2657);
DISPLAY 0.340426 (1380 2657);
PAINT GREEN (1380 2657);
DISPLAY INVISIBLE (1380 2657);
FORCEPROP 1 LAST VOLTAGE 0
J 0
(1425 2700);
PAINT SKYBLUE (1425 2700);
DISPLAY INVISIBLE (1425 2700);
FORCEPROP 2 LAST CDS_LIB mstr_symbols
J 0
(1425 2700);
PAINT ORANGE (1425 2700);
DISPLAY INVISIBLE (1425 2700);
FORCEPROP 1 LAST SIZE 1B
J 0
(1500 2650);
DISPLAY 1.170213 (1500 2650);
PAINT AQUA (1500 2650);
DISPLAY INVISIBLE (1500 2650);
FORCEPROP 1 LAST PATH I30
J 0
(1500 2700);
DISPLAY 0.872340 (1500 2700);
PAINT AQUA (1500 2700);
DISPLAY INVISIBLE (1500 2700);
FORCEPROP 1 LAST HDL_POWER GND
J 0
(1425 2850);
DISPLAY 1.170213 (1425 2850);
PAINT GREEN (1425 2850);
DISPLAY INVISIBLE (1425 2850);
FORCEADD CAP_A..1
(1025 2900);
FORCEPROP 1 LASTPIN (1025 2800) $PN 2
J 0
(1035 2780);
DISPLAY 0.617021 (1035 2780);
PAINT ORANGE (1035 2780);
FORCEPROP 1 LAST PACK_TYPE 0402V
J 0
(1075 2700);
DISPLAY 0.617021 (1075 2700);
PAINT SKYBLUE (1075 2700);
FORCEPROP 1 LAST MATERIAL X7R
J 0
(1075 2800);
DISPLAY 0.617021 (1075 2800);
PAINT SKYBLUE (1075 2800);
FORCEPROP 1 LASTPIN (1025 3000) $PN 1
J 0
(1035 2980);
DISPLAY 0.617021 (1035 2980);
PAINT ORANGE (1035 2980);
FORCEPROP 1 LAST LOCATION C7A38
J 0
(1075 3000);
DISPLAY 0.617021 (1075 3000);
PAINT AQUA (1075 3000);
FORCEPROP 1 LAST VALUE 0.1UF
J 0
(1075 2950);
DISPLAY 0.617021 (1075 2950);
PAINT SKYBLUE (1075 2950);
FORCEPROP 1 LAST TOLERANCE 10%
J 0
(1075 2850);
DISPLAY 0.617021 (1075 2850);
PAINT SKYBLUE (1075 2850);
FORCEPROP 1 LAST VOLTAGE 16V
J 0
(1075 2900);
DISPLAY 0.617021 (1075 2900);
PAINT SKYBLUE (1075 2900);
FORCEPROP 1 LAST PART_NUMBER A36096-030
J 0
(1075 2750);
DISPLAY 0.617021 (1075 2750);
PAINT BLUE (1075 2750);
FORCEPROP 2 LAST CDS_LOCATION C7A38
J 0
(1075 3000);
DISPLAY 0.617021 (1075 3000);
PAINT AQUA (1075 3000);
DISPLAY INVISIBLE (1075 3000);
FORCEPROP 2 LAST CDS_LIB dev_discrete
J 0
(1025 2900);
PAINT ORANGE (1025 2900);
DISPLAY INVISIBLE (1025 2900);
FORCEPROP 2 LAST CDS_SEC 1
J 0
(1075 3050);
PAINT ORANGE (1075 3050);
DISPLAY INVISIBLE (1075 3050);
FORCEPROP 2 LAST ROOM VDDQ_DEF_PWR_VR
J 0
(1075 3050);
DISPLAY 1.361702 (1075 3050);
PAINT ORANGE (1075 3050);
DISPLAY INVISIBLE (1075 3050);
FORCEPROP 1 LAST PATH I31
J 0
(1075 3050);
DISPLAY 0.978723 (1075 3050);
PAINT WHITE (1075 3050);
DISPLAY INVISIBLE (1075 3050);
FORCEPROP 2 LAST SEC_TYPE 0402V
J 0
(1075 3125);
DISPLAY 1.021277 (1075 3125);
PAINT ORANGE (1075 3125);
DISPLAY INVISIBLE (1075 3125);
FORCEPROP 2 LAST SEC 1
J 0
(1075 3125);
DISPLAY 0.680851 (1075 3125);
PAINT MONO (1075 3125);
DISPLAY INVISIBLE (1075 3125);
FORCEADD GND..1
(1025 2700);
FORCEPROP 3 LASTPIN (1025 2750) SIG_NAME GND\g
J 0
(1035 2760);
DISPLAY 0.659574 (1035 2760);
PAINT MONO (1035 2760);
DISPLAY INVISIBLE (1035 2760);
FORCEPROP 2 LAST ROOM VDDQ_DEF_PWR_VR
J 0
(450 2775);
DISPLAY 1.361702 (450 2775);
PAINT ORANGE (450 2775);
DISPLAY INVISIBLE (450 2775);
FORCEPROP 1 LAST BODY_TYPE PLUMBING
J 0
(980 2657);
DISPLAY 0.340426 (980 2657);
PAINT GREEN (980 2657);
DISPLAY INVISIBLE (980 2657);
FORCEPROP 1 LAST VOLTAGE 0
J 0
(1025 2700);
PAINT SKYBLUE (1025 2700);
DISPLAY INVISIBLE (1025 2700);
FORCEPROP 1 LAST SIZE 1B
J 0
(1100 2650);
DISPLAY 1.170213 (1100 2650);
PAINT AQUA (1100 2650);
DISPLAY INVISIBLE (1100 2650);
FORCEPROP 2 LAST CDS_LIB mstr_symbols
J 0
(1025 2700);
PAINT ORANGE (1025 2700);
DISPLAY INVISIBLE (1025 2700);
FORCEPROP 1 LAST PATH I32
J 0
(1100 2700);
DISPLAY 0.872340 (1100 2700);
PAINT AQUA (1100 2700);
DISPLAY INVISIBLE (1100 2700);
FORCEPROP 1 LAST HDL_POWER GND
J 0
(1025 2850);
DISPLAY 1.170213 (1025 2850);
PAINT GREEN (1025 2850);
DISPLAY INVISIBLE (1025 2850);
FORCEADD P3V3_STBY..1
(725 3750);
FORCEPROP 3 LASTPIN (725 3700) SIG_NAME P3V3_STBY\g
J 0
(735 3710);
DISPLAY 0.659574 (735 3710);
PAINT MONO (735 3710);
DISPLAY INVISIBLE (735 3710);
FORCEPROP 1 LAST HDL_POWER P3V3_STBY
J 0
(425 3625);
DISPLAY 0.872340 (425 3625);
PAINT ORANGE (425 3625);
DISPLAY INVISIBLE (425 3625);
FORCEPROP 1 LAST BODY_TYPE PLUMBING
J 0
(680 3707);
DISPLAY 0.340426 (680 3707);
PAINT GREEN (680 3707);
DISPLAY INVISIBLE (680 3707);
FORCEPROP 1 LAST VOLTAGE 3.3V
J 0
(680 3707);
DISPLAY 0.340426 (680 3707);
PAINT SKYBLUE (680 3707);
DISPLAY INVISIBLE (680 3707);
FORCEPROP 2 LAST CDS_LIB mstr_symbols
J 0
(725 3750);
PAINT ORANGE (725 3750);
DISPLAY INVISIBLE (725 3750);
FORCEPROP 1 LAST SIZE 1B
J 0
(770 3772);
DISPLAY 0.340426 (770 3772);
PAINT GREEN (770 3772);
DISPLAY INVISIBLE (770 3772);
FORCEPROP 1 LAST PATH I33
J 0
(770 3752);
DISPLAY 0.340426 (770 3752);
PAINT GREEN (770 3752);
DISPLAY INVISIBLE (770 3752);
FORCEADD RES..2
(725 3250);
FORCEPROP 1 LASTPIN (725 3150) $PN 2
J 0
(730 3160);
DISPLAY 0.617021 (730 3160);
PAINT ORANGE (730 3160);
FORCEPROP 1 LASTPIN (725 3350) $PN 1
J 0
(730 3312);
DISPLAY 0.617021 (730 3312);
PAINT ORANGE (730 3312);
FORCEPROP 1 LAST MATERIAL CHIP
J 0
(765 3175);
DISPLAY 0.617021 (765 3175);
PAINT SKYBLUE (765 3175);
FORCEPROP 1 LAST PACK_TYPE 0402
J 0
(765 3075);
DISPLAY 0.617021 (765 3075);
PAINT SKYBLUE (765 3075);
FORCEPROP 1 LAST WATTAGE 1/16W
J 0
(765 3225);
DISPLAY 0.617021 (765 3225);
PAINT SKYBLUE (765 3225);
FORCEPROP 1 LAST LOCATION R3M1
J 0
(770 3375);
DISPLAY 0.617021 (770 3375);
PAINT AQUA (770 3375);
FORCEPROP 1 LAST VALUE 0.0
J 0
(770 3325);
DISPLAY 0.617021 (770 3325);
PAINT SKYBLUE (770 3325);
FORCEPROP 1 LAST TOLERANCE 5%
J 0
(770 3275);
DISPLAY 0.617021 (770 3275);
PAINT SKYBLUE (770 3275);
FORCEPROP 1 LAST PART_NUMBER G21497-005
J 0
(765 3125);
DISPLAY 0.617021 (765 3125);
PAINT BLUE (765 3125);
FORCEPROP 2 LAST CDS_LIB mstr_discrete
J 0
(725 3250);
PAINT ORANGE (725 3250);
DISPLAY INVISIBLE (725 3250);
FORCEPROP 2 LAST SEC_TYPE 0402
J 0
(775 3500);
DISPLAY 1.021277 (775 3500);
PAINT ORANGE (775 3500);
DISPLAY INVISIBLE (775 3500);
FORCEPROP 2 LAST SEC 1
J 0
(775 3500);
DISPLAY 0.680851 (775 3500);
PAINT MONO (775 3500);
DISPLAY INVISIBLE (775 3500);
FORCEPROP 2 LAST CDS_LOCATION R3M1
J 0
(770 3375);
DISPLAY 0.617021 (770 3375);
PAINT AQUA (770 3375);
DISPLAY INVISIBLE (770 3375);
FORCEPROP 1 LAST PATH I34
J 0
(775 3425);
DISPLAY 0.978723 (775 3425);
PAINT WHITE (775 3425);
DISPLAY INVISIBLE (775 3425);
FORCEPROP 2 LAST ROOM VDDQ_DEF_PWR_VR
J 0
(775 3425);
DISPLAY 1.361702 (775 3425);
PAINT ORANGE (775 3425);
DISPLAY INVISIBLE (775 3425);
FORCEADD RES..2
(25 3325);
FORCEPROP 1 LAST WATTAGE 1/16W
J 0
(65 3300);
DISPLAY 0.617021 (65 3300);
PAINT SKYBLUE (65 3300);
FORCEPROP 1 LAST PACK_TYPE 0402
J 0
(65 3150);
DISPLAY 0.617021 (65 3150);
PAINT SKYBLUE (65 3150);
FORCEPROP 1 LAST MATERIAL EMPTY
J 0
(65 3250);
DISPLAY 0.617021 (65 3250);
PAINT RED (65 3250);
FORCEPROP 1 LAST TOLERANCE 1%
J 0
(70 3350);
DISPLAY 0.617021 (70 3350);
PAINT SKYBLUE (70 3350);
FORCEPROP 1 LAST VALUE 100.0K
J 0
(70 3400);
DISPLAY 0.617021 (70 3400);
PAINT SKYBLUE (70 3400);
FORCEPROP 1 LAST LOCATION R3M5
J 0
(70 3450);
DISPLAY 0.617021 (70 3450);
PAINT AQUA (70 3450);
FORCEPROP 1 LAST PART_NUMBER G21796-010
J 0
(65 3200);
DISPLAY 0.617021 (65 3200);
PAINT BLUE (65 3200);
FORCEPROP 1 LASTPIN (25 3225) $PN 2
J 0
(30 3235);
DISPLAY 0.787234 (30 3235);
PAINT ORANGE (30 3235);
DISPLAY INVISIBLE (30 3235);
FORCEPROP 2 LAST CDS_LIB mstr_discrete
J 0
(25 3325);
PAINT ORANGE (25 3325);
DISPLAY INVISIBLE (25 3325);
FORCEPROP 1 LASTPIN (25 3425) $PN 1
J 0
(30 3387);
DISPLAY 0.787234 (30 3387);
PAINT ORANGE (30 3387);
DISPLAY INVISIBLE (30 3387);
FORCEPROP 2 LAST CDS_LOCATION R3M5
J 0
(70 3450);
DISPLAY 0.617021 (70 3450);
PAINT AQUA (70 3450);
DISPLAY INVISIBLE (70 3450);
FORCEPROP 0 LAST ROOM VDDQ_DEF_PWR_VR
J 0
(75 3550);
DISPLAY 0.617021 (75 3550);
PAINT ORANGE (75 3550);
DISPLAY INVISIBLE (75 3550);
FORCEPROP 1 LAST PATH I35
J 0
(75 3500);
DISPLAY 0.978723 (75 3500);
PAINT WHITE (75 3500);
DISPLAY INVISIBLE (75 3500);
FORCEPROP 2 LAST $SEC 1
J 0
(75 3550);
PAINT MONO (75 3550);
DISPLAY INVISIBLE (75 3550);
FORCEPROP 2 LAST CDS_SEC 1
J 0
(75 3550);
PAINT MONO (75 3550);
DISPLAY INVISIBLE (75 3550);
FORCEPROP 0 LAST BOM_COST SM_CONTROLLER
J 0
(75 3650);
DISPLAY 1.021277 (75 3650);
PAINT ORANGE (75 3650);
DISPLAY INVISIBLE (75 3650);
FORCEADD RES..2
(400 100);
FORCEPROP 1 LAST PACK_TYPE 0402
J 0
(440 -75);
DISPLAY 0.617021 (440 -75);
PAINT SKYBLUE (440 -75);
FORCEPROP 1 LAST PART_NUMBER G21796-078
J 0
(440 -25);
DISPLAY 0.617021 (440 -25);
PAINT BLUE (440 -25);
FORCEPROP 1 LAST TOLERANCE 1%
J 0
(445 125);
DISPLAY 0.617021 (445 125);
PAINT SKYBLUE (445 125);
FORCEPROP 1 LAST WATTAGE 1/16W
J 0
(440 75);
DISPLAY 0.617021 (440 75);
PAINT SKYBLUE (440 75);
FORCEPROP 1 LAST MATERIAL CHIP
J 0
(440 25);
DISPLAY 0.617021 (440 25);
PAINT SKYBLUE (440 25);
FORCEPROP 1 LAST VALUE 8.06K
J 0
(445 175);
DISPLAY 0.617021 (445 175);
PAINT SKYBLUE (445 175);
FORCEPROP 1 LAST LOCATION R7A8
J 0
(445 225);
DISPLAY 0.617021 (445 225);
PAINT AQUA (445 225);
FORCEPROP 2 LAST CDS_LOCATION R7A8
J 0
(445 225);
DISPLAY 0.617021 (445 225);
PAINT AQUA (445 225);
DISPLAY INVISIBLE (445 225);
FORCEPROP 1 LASTPIN (400 200) $PN 1
J 0
(405 162);
DISPLAY 0.787234 (405 162);
PAINT ORANGE (405 162);
DISPLAY INVISIBLE (405 162);
FORCEPROP 1 LASTPIN (400 0) $PN 2
J 0
(405 10);
DISPLAY 0.787234 (405 10);
PAINT ORANGE (405 10);
DISPLAY INVISIBLE (405 10);
FORCEPROP 2 LAST CDS_LIB mstr_discrete
J 0
(400 100);
PAINT ORANGE (400 100);
DISPLAY INVISIBLE (400 100);
FORCEPROP 1 LAST PATH I37
J 0
(450 275);
DISPLAY 0.978723 (450 275);
PAINT WHITE (450 275);
DISPLAY INVISIBLE (450 275);
FORCEPROP 0 LAST ROOM VDDQ_DEF_PWR_VR
J 0
(450 325);
DISPLAY 1.021277 (450 325);
PAINT ORANGE (450 325);
DISPLAY INVISIBLE (450 325);
FORCEPROP 2 LAST $SEC 1
J 0
(450 325);
PAINT MONO (450 325);
DISPLAY INVISIBLE (450 325);
FORCEPROP 2 LAST CDS_SEC 1
J 0
(450 325);
PAINT MONO (450 325);
DISPLAY INVISIBLE (450 325);
FORCEADD GND..1
(0 650);
FORCEPROP 3 LASTPIN (0 700) SIG_NAME GND\g
J 0
(10 710);
DISPLAY 0.659574 (10 710);
PAINT MONO (10 710);
DISPLAY INVISIBLE (10 710);
FORCEPROP 2 LAST ROOM VDDQ_DEF_PWR_VR
J 0
(-575 725);
DISPLAY 1.361702 (-575 725);
PAINT ORANGE (-575 725);
DISPLAY INVISIBLE (-575 725);
FORCEPROP 1 LAST BODY_TYPE PLUMBING
J 0
(-45 607);
DISPLAY 0.340426 (-45 607);
PAINT GREEN (-45 607);
DISPLAY INVISIBLE (-45 607);
FORCEPROP 1 LAST HDL_POWER GND
J 0
(0 800);
DISPLAY 1.170213 (0 800);
PAINT GREEN (0 800);
DISPLAY INVISIBLE (0 800);
FORCEPROP 2 LAST CDS_LIB mstr_symbols
J 0
(0 650);
PAINT ORANGE (0 650);
DISPLAY INVISIBLE (0 650);
FORCEPROP 1 LAST VOLTAGE 0
J 0
(0 650);
PAINT SKYBLUE (0 650);
DISPLAY INVISIBLE (0 650);
FORCEPROP 1 LAST PATH I38
J 0
(75 650);
DISPLAY 0.872340 (75 650);
PAINT AQUA (75 650);
DISPLAY INVISIBLE (75 650);
FORCEPROP 1 LAST SIZE 1B
J 0
(75 600);
DISPLAY 1.170213 (75 600);
PAINT AQUA (75 600);
DISPLAY INVISIBLE (75 600);
FORCEADD CAP..1
R 2
(-75 550);
FORCEPROP 1 LASTPIN (-75 450) $PN 2
J 2
(-85 430);
DISPLAY 0.617021 (-85 430);
PAINT ORANGE (-85 430);
FORCEPROP 1 LAST PACK_TYPE 0402LF
J 2
(-125 450);
DISPLAY 0.617021 (-125 450);
PAINT SKYBLUE (-125 450);
FORCEPROP 1 LAST PART_NUMBER A36096-050
J 2
(-125 500);
DISPLAY 0.617021 (-125 500);
PAINT BLUE (-125 500);
FORCEPROP 1 LAST TOLERANCE 10%
J 2
(-300 600);
DISPLAY 0.617021 (-300 600);
PAINT SKYBLUE (-300 600);
FORCEPROP 1 LAST LOCATION C7A29
J 2
(-125 650);
DISPLAY 0.617021 (-125 650);
PAINT AQUA (-125 650);
FORCEPROP 1 LAST VALUE 220PF
J 2
(-125 600);
DISPLAY 0.617021 (-125 600);
PAINT SKYBLUE (-125 600);
FORCEPROP 1 LAST MATERIAL X7R
J 2
(-250 550);
DISPLAY 0.617021 (-250 550);
PAINT SKYBLUE (-250 550);
FORCEPROP 1 LASTPIN (-75 650) $PN 1
J 2
(-85 630);
DISPLAY 0.617021 (-85 630);
PAINT ORANGE (-85 630);
FORCEPROP 1 LAST VOLTAGE 50V
J 2
(-125 550);
DISPLAY 0.617021 (-125 550);
PAINT SKYBLUE (-125 550);
FORCEPROP 2 LAST SEC_TYPE 0402LF
J 2
(-125 775);
DISPLAY 1.021277 (-125 775);
PAINT ORANGE (-125 775);
DISPLAY INVISIBLE (-125 775);
FORCEPROP 2 LAST CDS_LIB mstr_discrete
J 2
(-75 550);
PAINT ORANGE (-75 550);
DISPLAY INVISIBLE (-75 550);
FORCEPROP 2 LAST ROOM VDDQ_DEF_PWR_VR
J 2
(-125 700);
DISPLAY 1.361702 (-125 700);
PAINT ORANGE (-125 700);
DISPLAY INVISIBLE (-125 700);
FORCEPROP 1 LAST PATH I39
J 2
(-125 700);
DISPLAY 0.978723 (-125 700);
PAINT WHITE (-125 700);
DISPLAY INVISIBLE (-125 700);
FORCEPROP 2 LAST CDS_LOCATION C7A29
J 2
(-125 650);
DISPLAY 0.617021 (-125 650);
PAINT AQUA (-125 650);
DISPLAY INVISIBLE (-125 650);
FORCEPROP 2 LAST SEC 1
J 2
(-125 775);
DISPLAY 0.680851 (-125 775);
PAINT MONO (-125 775);
DISPLAY INVISIBLE (-125 775);
FORCEADD OFFPAGE..1
R 2
(4100 175);
FORCEPROP 2 LAST $XR0 218 
J 0
(4286 175);
DISPLAY 0.638298 (4286 175);
PAINT MONO (4286 175);
FORCEPROP 2 LAST ROOM VDDQ_DEF_PWR_VR
J 0
(3675 250);
DISPLAY 1.361702 (3675 250);
PAINT ORANGE (3675 250);
DISPLAY INVISIBLE (3675 250);
FORCEPROP 1 LAST OFFPAGE TRUE
J 2
(3775 50);
DISPLAY 1.170213 (3775 50);
PAINT GREEN (3775 50);
DISPLAY INVISIBLE (3775 50);
FORCEPROP 1 LAST COMMENT_BODY TRUE
J 2
(3975 75);
DISPLAY 1.170213 (3975 75);
PAINT GREEN (3975 75);
DISPLAY INVISIBLE (3975 75);
FORCEPROP 2 LAST CDS_LIB mstr_standard
J 2
(4100 175);
PAINT ORANGE (4100 175);
DISPLAY INVISIBLE (4100 175);
FORCEPROP 2 LAST PATH I4
J 0
(4300 225);
DISPLAY 1.021277 (4300 225);
PAINT ORANGE (4300 225);
DISPLAY INVISIBLE (4300 225);
FORCEADD RES..2
(100 100);
FORCEPROP 1 LAST PACK_TYPE 0402
J 0
(140 -75);
DISPLAY 0.617021 (140 -75);
PAINT SKYBLUE (140 -75);
FORCEPROP 1 LAST PART_NUMBER G21796-043
J 0
(140 -25);
DISPLAY 0.617021 (140 -25);
PAINT BLUE (140 -25);
FORCEPROP 1 LAST TOLERANCE 1%
J 0
(145 125);
DISPLAY 0.617021 (145 125);
PAINT SKYBLUE (145 125);
FORCEPROP 1 LAST WATTAGE 1/16W
J 0
(140 75);
DISPLAY 0.617021 (140 75);
PAINT SKYBLUE (140 75);
FORCEPROP 1 LAST MATERIAL CHIP
J 0
(140 25);
DISPLAY 0.617021 (140 25);
PAINT SKYBLUE (140 25);
FORCEPROP 1 LAST VALUE 3.16K
J 0
(145 175);
DISPLAY 0.617021 (145 175);
PAINT SKYBLUE (145 175);
FORCEPROP 1 LAST LOCATION R7A10
J 0
(145 225);
DISPLAY 0.617021 (145 225);
PAINT AQUA (145 225);
FORCEPROP 1 LASTPIN (100 200) $PN 1
J 0
(105 162);
DISPLAY 0.787234 (105 162);
PAINT ORANGE (105 162);
DISPLAY INVISIBLE (105 162);
FORCEPROP 1 LASTPIN (100 0) $PN 2
J 0
(105 10);
DISPLAY 0.787234 (105 10);
PAINT ORANGE (105 10);
DISPLAY INVISIBLE (105 10);
FORCEPROP 2 LAST CDS_LIB mstr_discrete
J 0
(100 100);
PAINT ORANGE (100 100);
DISPLAY INVISIBLE (100 100);
FORCEPROP 2 LAST CDS_LOCATION R7A10
J 0
(145 225);
DISPLAY 0.617021 (145 225);
PAINT AQUA (145 225);
DISPLAY INVISIBLE (145 225);
FORCEPROP 1 LAST PATH I40
J 0
(150 275);
DISPLAY 0.978723 (150 275);
PAINT WHITE (150 275);
DISPLAY INVISIBLE (150 275);
FORCEPROP 2 LAST $SEC 1
J 0
(150 325);
PAINT MONO (150 325);
DISPLAY INVISIBLE (150 325);
FORCEPROP 2 LAST CDS_SEC 1
J 0
(150 325);
PAINT MONO (150 325);
DISPLAY INVISIBLE (150 325);
FORCEPROP 0 LAST ROOM VDDQ_DEF_PWR_VR
J 0
(150 325);
DISPLAY 1.021277 (150 325);
PAINT ORANGE (150 325);
DISPLAY INVISIBLE (150 325);
FORCEADD GND..1
(3525 -275);
FORCEPROP 3 LASTPIN (3525 -225) SIG_NAME GND\g
J 0
(3535 -215);
DISPLAY 0.659574 (3535 -215);
PAINT MONO (3535 -215);
DISPLAY INVISIBLE (3535 -215);
FORCEPROP 2 LAST ROOM VDDQ_DEF_PWR_VR
J 0
(2950 -200);
DISPLAY 1.361702 (2950 -200);
PAINT ORANGE (2950 -200);
DISPLAY INVISIBLE (2950 -200);
FORCEPROP 1 LAST BODY_TYPE PLUMBING
J 0
(3480 -318);
DISPLAY 0.340426 (3480 -318);
PAINT GREEN (3480 -318);
DISPLAY INVISIBLE (3480 -318);
FORCEPROP 1 LAST VOLTAGE 0
J 0
(3525 -275);
PAINT SKYBLUE (3525 -275);
DISPLAY INVISIBLE (3525 -275);
FORCEPROP 2 LAST CDS_LIB mstr_symbols
J 0
(3525 -275);
PAINT ORANGE (3525 -275);
DISPLAY INVISIBLE (3525 -275);
FORCEPROP 1 LAST HDL_POWER GND
J 0
(3525 -125);
DISPLAY 1.170213 (3525 -125);
PAINT GREEN (3525 -125);
DISPLAY INVISIBLE (3525 -125);
FORCEPROP 1 LAST PATH I41
J 0
(3600 -275);
DISPLAY 0.872340 (3600 -275);
PAINT AQUA (3600 -275);
DISPLAY INVISIBLE (3600 -275);
FORCEPROP 1 LAST SIZE 1B
J 0
(3600 -325);
DISPLAY 1.170213 (3600 -325);
PAINT AQUA (3600 -325);
DISPLAY INVISIBLE (3600 -325);
FORCEADD GND..1
(3125 -200);
FORCEPROP 3 LASTPIN (3125 -150) SIG_NAME GND\g
J 0
(3135 -140);
DISPLAY 0.659574 (3135 -140);
PAINT MONO (3135 -140);
DISPLAY INVISIBLE (3135 -140);
FORCEPROP 2 LAST ROOM VDDQ_DEF_PWR_VR
J 0
(2550 -125);
DISPLAY 1.361702 (2550 -125);
PAINT ORANGE (2550 -125);
DISPLAY INVISIBLE (2550 -125);
FORCEPROP 1 LAST VOLTAGE 0
J 0
(3125 -200);
PAINT SKYBLUE (3125 -200);
DISPLAY INVISIBLE (3125 -200);
FORCEPROP 2 LAST CDS_LIB mstr_symbols
J 0
(3125 -200);
PAINT ORANGE (3125 -200);
DISPLAY INVISIBLE (3125 -200);
FORCEPROP 1 LAST BODY_TYPE PLUMBING
J 0
(3080 -243);
DISPLAY 0.340426 (3080 -243);
PAINT GREEN (3080 -243);
DISPLAY INVISIBLE (3080 -243);
FORCEPROP 1 LAST HDL_POWER GND
J 0
(3125 -50);
DISPLAY 1.170213 (3125 -50);
PAINT GREEN (3125 -50);
DISPLAY INVISIBLE (3125 -50);
FORCEPROP 1 LAST PATH I42
J 0
(3200 -200);
DISPLAY 0.872340 (3200 -200);
PAINT AQUA (3200 -200);
DISPLAY INVISIBLE (3200 -200);
FORCEPROP 1 LAST SIZE 1B
J 0
(3200 -250);
DISPLAY 1.170213 (3200 -250);
PAINT AQUA (3200 -250);
DISPLAY INVISIBLE (3200 -250);
FORCEADD GND..1
(-75 -150);
FORCEPROP 3 LASTPIN (-75 -100) SIG_NAME GND\g
J 0
(-65 -90);
DISPLAY 0.659574 (-65 -90);
PAINT MONO (-65 -90);
DISPLAY INVISIBLE (-65 -90);
FORCEPROP 2 LAST ROOM VDDQ_DEF_PWR_VR
J 0
(-650 -75);
DISPLAY 1.361702 (-650 -75);
PAINT ORANGE (-650 -75);
DISPLAY INVISIBLE (-650 -75);
FORCEPROP 1 LAST BODY_TYPE PLUMBING
J 0
(-120 -193);
DISPLAY 0.340426 (-120 -193);
PAINT GREEN (-120 -193);
DISPLAY INVISIBLE (-120 -193);
FORCEPROP 2 LAST CDS_LIB mstr_symbols
J 0
(-75 -150);
PAINT ORANGE (-75 -150);
DISPLAY INVISIBLE (-75 -150);
FORCEPROP 1 LAST VOLTAGE 0
J 0
(-75 -150);
PAINT SKYBLUE (-75 -150);
DISPLAY INVISIBLE (-75 -150);
FORCEPROP 1 LAST HDL_POWER GND
J 0
(-75 0);
DISPLAY 1.170213 (-75 0);
PAINT GREEN (-75 0);
DISPLAY INVISIBLE (-75 0);
FORCEPROP 1 LAST PATH I43
J 0
(0 -150);
DISPLAY 0.872340 (0 -150);
PAINT AQUA (0 -150);
DISPLAY INVISIBLE (0 -150);
FORCEPROP 1 LAST SIZE 1B
J 0
(0 -200);
DISPLAY 1.170213 (0 -200);
PAINT AQUA (0 -200);
DISPLAY INVISIBLE (0 -200);
FORCEADD GND..1
(100 -150);
FORCEPROP 3 LASTPIN (100 -100) SIG_NAME GND\g
J 0
(110 -90);
DISPLAY 0.659574 (110 -90);
PAINT MONO (110 -90);
DISPLAY INVISIBLE (110 -90);
FORCEPROP 2 LAST ROOM VDDQ_DEF_PWR_VR
J 0
(-475 -75);
DISPLAY 1.361702 (-475 -75);
PAINT ORANGE (-475 -75);
DISPLAY INVISIBLE (-475 -75);
FORCEPROP 1 LAST PATH I44
J 0
(175 -150);
DISPLAY 0.872340 (175 -150);
PAINT AQUA (175 -150);
DISPLAY INVISIBLE (175 -150);
FORCEPROP 1 LAST BODY_TYPE PLUMBING
J 0
(55 -193);
DISPLAY 0.340426 (55 -193);
PAINT GREEN (55 -193);
DISPLAY INVISIBLE (55 -193);
FORCEPROP 1 LAST SIZE 1B
J 0
(175 -200);
DISPLAY 1.170213 (175 -200);
PAINT AQUA (175 -200);
DISPLAY INVISIBLE (175 -200);
FORCEPROP 2 LAST CDS_LIB mstr_symbols
J 0
(100 -150);
PAINT ORANGE (100 -150);
DISPLAY INVISIBLE (100 -150);
FORCEPROP 1 LAST VOLTAGE 0
J 0
(100 -150);
PAINT SKYBLUE (100 -150);
DISPLAY INVISIBLE (100 -150);
FORCEPROP 1 LAST HDL_POWER GND
J 0
(100 0);
DISPLAY 1.170213 (100 0);
PAINT GREEN (100 0);
DISPLAY INVISIBLE (100 0);
FORCEADD GND..1
(400 -150);
FORCEPROP 3 LASTPIN (400 -100) SIG_NAME GND\g
J 0
(410 -90);
DISPLAY 0.659574 (410 -90);
PAINT MONO (410 -90);
DISPLAY INVISIBLE (410 -90);
FORCEPROP 2 LAST ROOM VDDQ_DEF_PWR_VR
J 0
(-175 -75);
DISPLAY 1.361702 (-175 -75);
PAINT ORANGE (-175 -75);
DISPLAY INVISIBLE (-175 -75);
FORCEPROP 2 LAST CDS_LIB mstr_symbols
J 0
(400 -150);
PAINT ORANGE (400 -150);
DISPLAY INVISIBLE (400 -150);
FORCEPROP 1 LAST SIZE 1B
J 0
(475 -200);
DISPLAY 1.170213 (475 -200);
PAINT AQUA (475 -200);
DISPLAY INVISIBLE (475 -200);
FORCEPROP 1 LAST BODY_TYPE PLUMBING
J 0
(355 -193);
DISPLAY 0.340426 (355 -193);
PAINT GREEN (355 -193);
DISPLAY INVISIBLE (355 -193);
FORCEPROP 1 LAST PATH I45
J 0
(475 -150);
DISPLAY 0.872340 (475 -150);
PAINT AQUA (475 -150);
DISPLAY INVISIBLE (475 -150);
FORCEPROP 1 LAST VOLTAGE 0
J 0
(400 -150);
PAINT SKYBLUE (400 -150);
DISPLAY INVISIBLE (400 -150);
FORCEPROP 1 LAST HDL_POWER GND
J 0
(400 0);
DISPLAY 1.170213 (400 0);
PAINT GREEN (400 0);
DISPLAY INVISIBLE (400 0);
FORCEADD PVCCIO_CPU0..1
(-725 3775);
FORCEPROP 3 LASTPIN (-725 3725) SIG_NAME PVCCIO_CPU0\g
J 0
(-715 3735);
DISPLAY 0.659574 (-715 3735);
PAINT MONO (-715 3735);
DISPLAY INVISIBLE (-715 3735);
FORCEPROP 1 LAST HDL_POWER PVCCIO_CPU0
J 1
(-725 3825);
DISPLAY 0.872340 (-725 3825);
PAINT GREEN (-725 3825);
DISPLAY INVISIBLE (-725 3825);
FORCEPROP 1 LAST PATH I46
J 0
(-675 3800);
DISPLAY 0.872340 (-675 3800);
PAINT AQUA (-675 3800);
DISPLAY INVISIBLE (-675 3800);
FORCEPROP 1 LAST BODY_TYPE PLUMBING
J 0
(-770 3732);
DISPLAY 0.340426 (-770 3732);
PAINT GREEN (-770 3732);
DISPLAY INVISIBLE (-770 3732);
FORCEPROP 2 LAST CDS_LIB mstr_symbols
J 0
(-725 3775);
PAINT ORANGE (-725 3775);
DISPLAY INVISIBLE (-725 3775);
FORCEPROP 1 LAST VOLTAGE 1.1V
J 0
(-770 3732);
DISPLAY 0.340426 (-770 3732);
PAINT SKYBLUE (-770 3732);
DISPLAY INVISIBLE (-770 3732);
FORCEADD RES..2
(-725 3350);
FORCEPROP 1 LASTPIN (-725 3250) $PN 2
J 0
(-720 3260);
DISPLAY 0.617021 (-720 3260);
PAINT ORANGE (-720 3260);
FORCEPROP 1 LAST PACK_TYPE 0402
J 0
(-685 3175);
DISPLAY 0.617021 (-685 3175);
PAINT SKYBLUE (-685 3175);
FORCEPROP 1 LAST WATTAGE 1/16W
J 0
(-685 3325);
DISPLAY 0.617021 (-685 3325);
PAINT SKYBLUE (-685 3325);
FORCEPROP 1 LASTPIN (-725 3450) $PN 1
J 0
(-720 3412);
DISPLAY 0.617021 (-720 3412);
PAINT ORANGE (-720 3412);
FORCEPROP 1 LAST TOLERANCE 1%
J 0
(-680 3375);
DISPLAY 0.617021 (-680 3375);
PAINT SKYBLUE (-680 3375);
FORCEPROP 1 LAST VALUE 49.9
J 0
(-680 3425);
DISPLAY 0.617021 (-680 3425);
PAINT SKYBLUE (-680 3425);
FORCEPROP 1 LAST LOCATION R3L13
J 0
(-680 3475);
DISPLAY 0.617021 (-680 3475);
PAINT AQUA (-680 3475);
FORCEPROP 1 LAST PART_NUMBER G21796-047
J 0
(-685 3225);
DISPLAY 0.617021 (-685 3225);
PAINT BLUE (-685 3225);
FORCEPROP 1 LAST MATERIAL CHIP
J 0
(-685 3275);
PAINT SKYBLUE (-685 3275);
DISPLAY INVISIBLE (-685 3275);
FORCEPROP 2 LAST ROOM VDDQ_DEF_PWR_VR
J 0
(-675 3525);
DISPLAY 1.361702 (-675 3525);
PAINT ORANGE (-675 3525);
DISPLAY INVISIBLE (-675 3525);
FORCEPROP 1 LAST PATH I47
J 0
(-675 3525);
DISPLAY 0.978723 (-675 3525);
PAINT WHITE (-675 3525);
DISPLAY INVISIBLE (-675 3525);
FORCEPROP 2 LAST CDS_LOCATION R3L13
J 0
(-680 3475);
DISPLAY 0.617021 (-680 3475);
PAINT AQUA (-680 3475);
DISPLAY INVISIBLE (-680 3475);
FORCEPROP 2 LAST CDS_LIB mstr_discrete
J 0
(-725 3350);
PAINT ORANGE (-725 3350);
DISPLAY INVISIBLE (-725 3350);
FORCEPROP 2 LAST SEC 1
J 0
(-675 3600);
PAINT MONO (-675 3600);
DISPLAY INVISIBLE (-675 3600);
FORCEPROP 2 LAST SEC_TYPE 0402
J 0
(-675 3600);
DISPLAY 1.021277 (-675 3600);
PAINT ORANGE (-675 3600);
DISPLAY INVISIBLE (-675 3600);
FORCEADD RES..1
(-300 2825);
FORCEPROP 1 LAST VALUE 150.0
J 2
(-300 2900);
DISPLAY 0.617021 (-300 2900);
PAINT SKYBLUE (-300 2900);
FORCEPROP 1 LASTPIN (-400 2825) $PN 1
J 0
(-388 2837);
DISPLAY 0.617021 (-388 2837);
PAINT ORANGE (-388 2837);
FORCEPROP 1 LAST LOCATION R7A17
J 0
(-400 3000);
DISPLAY 0.617021 (-400 3000);
PAINT AQUA (-400 3000);
FORCEPROP 1 LAST PART_NUMBER G21796-009
J 0
(-400 2950);
DISPLAY 0.617021 (-400 2950);
PAINT BLUE (-400 2950);
FORCEPROP 1 LAST WATTAGE 1/16W
J 2
(-250 2850);
DISPLAY 0.617021 (-250 2850);
PAINT SKYBLUE (-250 2850);
FORCEPROP 1 LASTPIN (-200 2825) $PN 2
J 0
(-238 2837);
DISPLAY 0.617021 (-238 2837);
PAINT ORANGE (-238 2837);
FORCEPROP 1 LAST MATERIAL CHIP
J 0
(-200 2850);
DISPLAY 0.617021 (-200 2850);
PAINT SKYBLUE (-200 2850);
FORCEPROP 1 LAST PACK_TYPE 0402
J 0
(-125 2900);
DISPLAY 0.617021 (-125 2900);
PAINT SKYBLUE (-125 2900);
FORCEPROP 1 LAST TOLERANCE 1%
J 0
(-250 2900);
DISPLAY 0.617021 (-250 2900);
PAINT SKYBLUE (-250 2900);
FORCEPROP 1 LAST PATH I48
J 0
(-350 2975);
DISPLAY 0.978723 (-350 2975);
PAINT WHITE (-350 2975);
DISPLAY INVISIBLE (-350 2975);
FORCEPROP 2 LAST CDS_LIB mstr_discrete
J 0
(-300 2825);
PAINT ORANGE (-300 2825);
DISPLAY INVISIBLE (-300 2825);
FORCEPROP 2 LAST CDS_LOCATION R7A17
J 0
(-400 3000);
DISPLAY 0.617021 (-400 3000);
PAINT AQUA (-400 3000);
DISPLAY INVISIBLE (-400 3000);
FORCEPROP 2 LAST ROOM VDDQ_DEF_PWR_VR
J 0
(-400 3050);
DISPLAY 1.361702 (-400 3050);
PAINT ORANGE (-400 3050);
DISPLAY INVISIBLE (-400 3050);
FORCEPROP 2 LAST SEC 1
J 0
(-350 3050);
DISPLAY 0.680851 (-350 3050);
PAINT MONO (-350 3050);
DISPLAY INVISIBLE (-350 3050);
FORCEPROP 2 LAST SEC_TYPE 0402
J 0
(-350 3050);
DISPLAY 1.021277 (-350 3050);
PAINT ORANGE (-350 3050);
DISPLAY INVISIBLE (-350 3050);
FORCEADD RES..1
(-825 2650);
FORCEPROP 1 LAST MATERIAL CHIP
J 0
(-825 2500);
DISPLAY 0.617021 (-825 2500);
PAINT SKYBLUE (-825 2500);
FORCEPROP 1 LAST WATTAGE 1/16W
J 2
(-850 2500);
DISPLAY 0.617021 (-850 2500);
PAINT SKYBLUE (-850 2500);
FORCEPROP 1 LAST PACK_TYPE 0402
J 0
(-750 2550);
DISPLAY 0.617021 (-750 2550);
PAINT SKYBLUE (-750 2550);
FORCEPROP 1 LAST TOLERANCE 5%
J 0
(-875 2550);
DISPLAY 0.617021 (-875 2550);
PAINT SKYBLUE (-875 2550);
FORCEPROP 1 LAST VALUE 0.0
J 2
(-925 2550);
DISPLAY 0.617021 (-925 2550);
PAINT SKYBLUE (-925 2550);
FORCEPROP 1 LAST LOCATION R3L10
J 0
(-875 2700);
DISPLAY 0.617021 (-875 2700);
PAINT AQUA (-875 2700);
FORCEPROP 1 LAST PART_NUMBER G21497-005
J 0
(-975 2600);
DISPLAY 0.617021 (-975 2600);
PAINT BLUE (-975 2600);
FORCEPROP 2 LAST ROOM VDDQ_DEF_PWR_VR
J 0
(-875 2750);
DISPLAY 1.361702 (-875 2750);
PAINT ORANGE (-875 2750);
DISPLAY INVISIBLE (-875 2750);
FORCEPROP 2 LAST CDS_LOCATION R3L10
J 0
(-875 2700);
DISPLAY 0.617021 (-875 2700);
PAINT AQUA (-875 2700);
DISPLAY INVISIBLE (-875 2700);
FORCEPROP 2 LAST CDS_LIB mstr_discrete
J 0
(-825 2650);
PAINT ORANGE (-825 2650);
DISPLAY INVISIBLE (-825 2650);
FORCEPROP 1 LASTPIN (-925 2650) $PN 1
J 0
(-913 2662);
DISPLAY 0.787234 (-913 2662);
PAINT ORANGE (-913 2662);
DISPLAY INVISIBLE (-913 2662);
FORCEPROP 1 LAST PATH I50
J 0
(-875 2800);
DISPLAY 0.978723 (-875 2800);
PAINT WHITE (-875 2800);
DISPLAY INVISIBLE (-875 2800);
FORCEPROP 2 LAST $SEC 1
J 0
(-875 2850);
PAINT MONO (-875 2850);
DISPLAY INVISIBLE (-875 2850);
FORCEPROP 2 LAST CDS_SEC 1
J 0
(-875 2850);
PAINT MONO (-875 2850);
DISPLAY INVISIBLE (-875 2850);
FORCEPROP 1 LASTPIN (-725 2650) $PN 2
J 0
(-763 2662);
DISPLAY 0.787234 (-763 2662);
PAINT ORANGE (-763 2662);
DISPLAY INVISIBLE (-763 2662);
FORCEADD VCC_CORE..1
(-1350 3775);
FORCEPROP 3 LASTPIN (-1350 3725) SIG_NAME VR_FET_SW_P12V_STBY_PVDDQ_DEF\g
J 0
(-1340 3735);
DISPLAY 0.659574 (-1340 3735);
PAINT MONO (-1340 3735);
DISPLAY INVISIBLE (-1340 3735);
FORCEPROP 1 LAST HDL_POWER VR_FET_SW_P12V_STBY_PVDDQ_DEF
J 1
(-1350 3825);
DISPLAY 0.617021 (-1350 3825);
PAINT GREEN (-1350 3825);
FORCEPROP 1 LAST PATH I52
J 0
(-1300 3800);
DISPLAY 0.872340 (-1300 3800);
PAINT AQUA (-1300 3800);
DISPLAY INVISIBLE (-1300 3800);
FORCEPROP 2 LAST CDS_LIB mstr_symbols
J 0
(-1350 3775);
PAINT ORANGE (-1350 3775);
DISPLAY INVISIBLE (-1350 3775);
FORCEADD RES..2
(-1350 3550);
FORCEPROP 1 LASTPIN (-1350 3450) $PN 2
J 0
(-1345 3460);
DISPLAY 0.617021 (-1345 3460);
PAINT ORANGE (-1345 3460);
FORCEPROP 1 LAST WATTAGE 1/16W
J 0
(-1310 3525);
DISPLAY 0.617021 (-1310 3525);
PAINT SKYBLUE (-1310 3525);
FORCEPROP 1 LAST MATERIAL CHIP
J 0
(-1310 3475);
DISPLAY 0.617021 (-1310 3475);
PAINT SKYBLUE (-1310 3475);
FORCEPROP 1 LAST PACK_TYPE 0402
J 0
(-1310 3375);
DISPLAY 0.617021 (-1310 3375);
PAINT SKYBLUE (-1310 3375);
FORCEPROP 1 LAST TOLERANCE 1%
J 0
(-1305 3575);
DISPLAY 0.617021 (-1305 3575);
PAINT SKYBLUE (-1305 3575);
FORCEPROP 1 LASTPIN (-1350 3650) $PN 1
J 0
(-1345 3612);
DISPLAY 0.617021 (-1345 3612);
PAINT ORANGE (-1345 3612);
FORCEPROP 1 LAST LOCATION R3L12
J 0
(-1305 3675);
DISPLAY 0.617021 (-1305 3675);
PAINT AQUA (-1305 3675);
FORCEPROP 1 LAST VALUE 100.0K
J 0
(-1305 3625);
DISPLAY 0.617021 (-1305 3625);
PAINT SKYBLUE (-1305 3625);
FORCEPROP 1 LAST PART_NUMBER G21796-160
J 0
(-1310 3425);
DISPLAY 0.617021 (-1310 3425);
PAINT BLUE (-1310 3425);
FORCEPROP 2 LAST CDS_LIB mstr_discrete
J 0
(-1350 3550);
PAINT ORANGE (-1350 3550);
DISPLAY INVISIBLE (-1350 3550);
FORCEPROP 2 LAST CDS_LOCATION R3L12
J 0
(-1305 3675);
DISPLAY 0.617021 (-1305 3675);
PAINT AQUA (-1305 3675);
DISPLAY INVISIBLE (-1305 3675);
FORCEPROP 2 LAST ROOM VDDQ_DEF_PWR_VR
J 0
(-1300 3725);
DISPLAY 1.361702 (-1300 3725);
PAINT ORANGE (-1300 3725);
DISPLAY INVISIBLE (-1300 3725);
FORCEPROP 1 LAST PATH I53
J 0
(-1300 3725);
DISPLAY 0.978723 (-1300 3725);
PAINT WHITE (-1300 3725);
DISPLAY INVISIBLE (-1300 3725);
FORCEPROP 2 LAST SEC 1
J 0
(-1300 3775);
DISPLAY 0.680851 (-1300 3775);
PAINT MONO (-1300 3775);
DISPLAY INVISIBLE (-1300 3775);
FORCEPROP 2 LAST SEC_TYPE 0402
J 0
(-1300 3775);
DISPLAY 1.021277 (-1300 3775);
PAINT ORANGE (-1300 3775);
DISPLAY INVISIBLE (-1300 3775);
FORCEADD RES..2
(-1350 3175);
FORCEPROP 1 LAST PACK_TYPE 0402
J 0
(-1310 3000);
DISPLAY 0.617021 (-1310 3000);
PAINT SKYBLUE (-1310 3000);
FORCEPROP 1 LASTPIN (-1350 3075) $PN 2
J 0
(-1345 3085);
DISPLAY 0.617021 (-1345 3085);
PAINT ORANGE (-1345 3085);
FORCEPROP 1 LASTPIN (-1350 3275) $PN 1
J 0
(-1345 3237);
DISPLAY 0.617021 (-1345 3237);
PAINT ORANGE (-1345 3237);
FORCEPROP 1 LAST WATTAGE 1/16W
J 0
(-1310 3150);
DISPLAY 0.617021 (-1310 3150);
PAINT SKYBLUE (-1310 3150);
FORCEPROP 1 LAST MATERIAL CHIP
J 0
(-1310 3100);
DISPLAY 0.617021 (-1310 3100);
PAINT SKYBLUE (-1310 3100);
FORCEPROP 1 LAST TOLERANCE 1%
J 0
(-1305 3200);
DISPLAY 0.617021 (-1305 3200);
PAINT SKYBLUE (-1305 3200);
FORCEPROP 1 LAST VALUE 1.5K
J 0
(-1305 3250);
DISPLAY 0.617021 (-1305 3250);
PAINT SKYBLUE (-1305 3250);
FORCEPROP 1 LAST LOCATION R7A16
J 0
(-1305 3300);
DISPLAY 0.617021 (-1305 3300);
PAINT AQUA (-1305 3300);
FORCEPROP 1 LAST PART_NUMBER G21796-003
J 0
(-1310 3050);
DISPLAY 0.617021 (-1310 3050);
PAINT BLUE (-1310 3050);
FORCEPROP 2 LAST CDS_LIB mstr_discrete
J 0
(-1350 3175);
PAINT ORANGE (-1350 3175);
DISPLAY INVISIBLE (-1350 3175);
FORCEPROP 2 LAST CDS_LOCATION R7A16
J 0
(-1305 3300);
DISPLAY 0.617021 (-1305 3300);
PAINT AQUA (-1305 3300);
DISPLAY INVISIBLE (-1305 3300);
FORCEPROP 2 LAST ROOM VDDQ_DEF_PWR_VR
J 0
(-1300 3350);
DISPLAY 1.361702 (-1300 3350);
PAINT ORANGE (-1300 3350);
DISPLAY INVISIBLE (-1300 3350);
FORCEPROP 1 LAST PATH I54
J 0
(-1300 3350);
DISPLAY 0.978723 (-1300 3350);
PAINT WHITE (-1300 3350);
DISPLAY INVISIBLE (-1300 3350);
FORCEPROP 2 LAST SEC 1
J 0
(-1300 3400);
DISPLAY 0.680851 (-1300 3400);
PAINT MONO (-1300 3400);
DISPLAY INVISIBLE (-1300 3400);
FORCEPROP 2 LAST SEC_TYPE 0402
J 0
(-1300 3400);
DISPLAY 1.021277 (-1300 3400);
PAINT ORANGE (-1300 3400);
DISPLAY INVISIBLE (-1300 3400);
FORCEADD CAP..1
R 2
(-1575 3175);
FORCEPROP 1 LAST PACK_TYPE 0402LF
J 2
(-1625 2975);
DISPLAY 0.617021 (-1625 2975);
PAINT SKYBLUE (-1625 2975);
FORCEPROP 1 LASTPIN (-1575 3075) $PN 2
J 2
(-1585 3055);
DISPLAY 0.617021 (-1585 3055);
PAINT ORANGE (-1585 3055);
FORCEPROP 1 LAST VALUE 1000PF
J 2
(-1625 3225);
DISPLAY 0.617021 (-1625 3225);
PAINT SKYBLUE (-1625 3225);
FORCEPROP 1 LAST LOCATION C7A35
J 2
(-1625 3275);
DISPLAY 0.617021 (-1625 3275);
PAINT AQUA (-1625 3275);
FORCEPROP 1 LAST VOLTAGE 50V
J 2
(-1625 3175);
DISPLAY 0.617021 (-1625 3175);
PAINT SKYBLUE (-1625 3175);
FORCEPROP 1 LASTPIN (-1575 3275) $PN 1
J 2
(-1585 3255);
DISPLAY 0.617021 (-1585 3255);
PAINT ORANGE (-1585 3255);
FORCEPROP 1 LAST PART_NUMBER A36096-046
J 2
(-1625 3025);
DISPLAY 0.617021 (-1625 3025);
PAINT BLUE (-1625 3025);
FORCEPROP 1 LAST MATERIAL X7R
J 2
(-1625 3075);
DISPLAY 0.617021 (-1625 3075);
PAINT SKYBLUE (-1625 3075);
FORCEPROP 1 LAST TOLERANCE 10%
J 2
(-1625 3125);
DISPLAY 0.617021 (-1625 3125);
PAINT SKYBLUE (-1625 3125);
FORCEPROP 2 LAST CDS_LIB mstr_discrete
J 2
(-1575 3175);
PAINT ORANGE (-1575 3175);
DISPLAY INVISIBLE (-1575 3175);
FORCEPROP 2 LAST CDS_LOCATION C7A35
J 2
(-1625 3275);
DISPLAY 0.617021 (-1625 3275);
PAINT AQUA (-1625 3275);
DISPLAY INVISIBLE (-1625 3275);
FORCEPROP 1 LAST PATH I55
J 2
(-1625 3325);
DISPLAY 0.978723 (-1625 3325);
PAINT WHITE (-1625 3325);
DISPLAY INVISIBLE (-1625 3325);
FORCEPROP 2 LAST ROOM VDDQ_DEF_PWR_VR
J 0
(-1625 3325);
DISPLAY 1.361702 (-1625 3325);
PAINT ORANGE (-1625 3325);
DISPLAY INVISIBLE (-1625 3325);
FORCEPROP 2 LAST SEC 1
J 0
(-1625 3400);
DISPLAY 0.680851 (-1625 3400);
PAINT MONO (-1625 3400);
DISPLAY INVISIBLE (-1625 3400);
FORCEPROP 2 LAST SEC_TYPE 0402LF
J 0
(-1625 3400);
DISPLAY 1.021277 (-1625 3400);
PAINT ORANGE (-1625 3400);
DISPLAY INVISIBLE (-1625 3400);
FORCEADD GND..1
(-1350 2925);
FORCEPROP 3 LASTPIN (-1350 2975) SIG_NAME GND\g
J 0
(-1340 2985);
DISPLAY 0.659574 (-1340 2985);
PAINT MONO (-1340 2985);
DISPLAY INVISIBLE (-1340 2985);
FORCEPROP 2 LAST ROOM VDDQ_DEF_PWR_VR
J 0
(-1925 3000);
DISPLAY 1.361702 (-1925 3000);
PAINT ORANGE (-1925 3000);
DISPLAY INVISIBLE (-1925 3000);
FORCEPROP 1 LAST VOLTAGE 0
J 0
(-1350 2925);
PAINT SKYBLUE (-1350 2925);
DISPLAY INVISIBLE (-1350 2925);
FORCEPROP 1 LAST BODY_TYPE PLUMBING
J 0
(-1395 2882);
DISPLAY 0.340426 (-1395 2882);
PAINT GREEN (-1395 2882);
DISPLAY INVISIBLE (-1395 2882);
FORCEPROP 2 LAST CDS_LIB mstr_symbols
J 0
(-1350 2925);
PAINT ORANGE (-1350 2925);
DISPLAY INVISIBLE (-1350 2925);
FORCEPROP 1 LAST SIZE 1B
J 0
(-1275 2875);
DISPLAY 1.170213 (-1275 2875);
PAINT AQUA (-1275 2875);
DISPLAY INVISIBLE (-1275 2875);
FORCEPROP 1 LAST PATH I56
J 0
(-1275 2925);
DISPLAY 0.872340 (-1275 2925);
PAINT AQUA (-1275 2925);
DISPLAY INVISIBLE (-1275 2925);
FORCEPROP 1 LAST HDL_POWER GND
J 0
(-1350 3075);
DISPLAY 1.170213 (-1350 3075);
PAINT GREEN (-1350 3075);
DISPLAY INVISIBLE (-1350 3075);
FORCEADD RES..1
(-1400 2475);
FORCEPROP 1 LAST WATTAGE 1/16W
J 2
(-1425 2325);
DISPLAY 0.617021 (-1425 2325);
PAINT SKYBLUE (-1425 2325);
FORCEPROP 1 LAST VALUE 0.0
J 2
(-1500 2375);
DISPLAY 0.617021 (-1500 2375);
PAINT SKYBLUE (-1500 2375);
FORCEPROP 1 LAST PART_NUMBER G21497-005
J 0
(-1550 2425);
DISPLAY 0.617021 (-1550 2425);
PAINT BLUE (-1550 2425);
FORCEPROP 1 LAST TOLERANCE 5%
J 0
(-1450 2375);
DISPLAY 0.617021 (-1450 2375);
PAINT SKYBLUE (-1450 2375);
FORCEPROP 1 LAST LOCATION R3L9
J 0
(-1450 2525);
DISPLAY 0.617021 (-1450 2525);
PAINT AQUA (-1450 2525);
FORCEPROP 1 LAST MATERIAL CHIP
J 0
(-1400 2325);
DISPLAY 0.617021 (-1400 2325);
PAINT SKYBLUE (-1400 2325);
FORCEPROP 1 LAST PACK_TYPE 0402
J 0
(-1325 2375);
DISPLAY 0.617021 (-1325 2375);
PAINT SKYBLUE (-1325 2375);
FORCEPROP 1 LASTPIN (-1500 2475) $PN 1
J 0
(-1488 2487);
DISPLAY 0.787234 (-1488 2487);
PAINT ORANGE (-1488 2487);
DISPLAY INVISIBLE (-1488 2487);
FORCEPROP 2 LAST CDS_LOCATION R3L9
J 0
(-1450 2525);
DISPLAY 0.617021 (-1450 2525);
PAINT AQUA (-1450 2525);
DISPLAY INVISIBLE (-1450 2525);
FORCEPROP 2 LAST CDS_LIB mstr_discrete
J 0
(-1400 2475);
PAINT ORANGE (-1400 2475);
DISPLAY INVISIBLE (-1400 2475);
FORCEPROP 1 LASTPIN (-1300 2475) $PN 2
J 0
(-1338 2487);
DISPLAY 0.787234 (-1338 2487);
PAINT ORANGE (-1338 2487);
DISPLAY INVISIBLE (-1338 2487);
FORCEPROP 2 LAST ROOM VDDQ_DEF_PWR_VR
J 0
(-1450 2575);
DISPLAY 1.361702 (-1450 2575);
PAINT ORANGE (-1450 2575);
DISPLAY INVISIBLE (-1450 2575);
FORCEPROP 1 LAST PATH I57
J 0
(-1450 2625);
DISPLAY 0.978723 (-1450 2625);
PAINT WHITE (-1450 2625);
DISPLAY INVISIBLE (-1450 2625);
FORCEPROP 2 LAST $SEC 1
J 0
(-1450 2675);
PAINT MONO (-1450 2675);
DISPLAY INVISIBLE (-1450 2675);
FORCEPROP 2 LAST CDS_SEC 1
J 0
(-1450 2675);
PAINT MONO (-1450 2675);
DISPLAY INVISIBLE (-1450 2675);
FORCEADD GND..1
(-1575 2925);
FORCEPROP 3 LASTPIN (-1575 2975) SIG_NAME GND\g
J 0
(-1565 2985);
DISPLAY 0.659574 (-1565 2985);
PAINT MONO (-1565 2985);
DISPLAY INVISIBLE (-1565 2985);
FORCEPROP 2 LAST ROOM VDDQ_DEF_PWR_VR
J 0
(-2150 3000);
DISPLAY 1.361702 (-2150 3000);
PAINT ORANGE (-2150 3000);
DISPLAY INVISIBLE (-2150 3000);
FORCEPROP 1 LAST VOLTAGE 0
J 0
(-1575 2925);
PAINT SKYBLUE (-1575 2925);
DISPLAY INVISIBLE (-1575 2925);
FORCEPROP 2 LAST CDS_LIB mstr_symbols
J 0
(-1575 2925);
PAINT ORANGE (-1575 2925);
DISPLAY INVISIBLE (-1575 2925);
FORCEPROP 1 LAST BODY_TYPE PLUMBING
J 0
(-1620 2882);
DISPLAY 0.340426 (-1620 2882);
PAINT GREEN (-1620 2882);
DISPLAY INVISIBLE (-1620 2882);
FORCEPROP 1 LAST PATH I58
J 0
(-1500 2925);
DISPLAY 0.872340 (-1500 2925);
PAINT AQUA (-1500 2925);
DISPLAY INVISIBLE (-1500 2925);
FORCEPROP 1 LAST SIZE 1B
J 0
(-1500 2875);
DISPLAY 1.170213 (-1500 2875);
PAINT AQUA (-1500 2875);
DISPLAY INVISIBLE (-1500 2875);
FORCEPROP 1 LAST HDL_POWER GND
J 0
(-1575 3075);
DISPLAY 1.170213 (-1575 3075);
PAINT GREEN (-1575 3075);
DISPLAY INVISIBLE (-1575 3075);
FORCEADD RES..1
(-1725 1300);
FORCEPROP 1 LAST VALUE 0.0
J 2
(-1825 1200);
DISPLAY 0.617021 (-1825 1200);
PAINT SKYBLUE (-1825 1200);
FORCEPROP 1 LAST WATTAGE 1/16W
J 2
(-1750 1150);
DISPLAY 0.617021 (-1750 1150);
PAINT SKYBLUE (-1750 1150);
FORCEPROP 1 LAST PART_NUMBER G21497-005
J 0
(-1875 1250);
DISPLAY 0.617021 (-1875 1250);
PAINT BLUE (-1875 1250);
FORCEPROP 1 LAST MATERIAL CHIP
J 0
(-1725 1150);
DISPLAY 0.617021 (-1725 1150);
PAINT SKYBLUE (-1725 1150);
FORCEPROP 1 LAST TOLERANCE 5%
J 0
(-1775 1200);
DISPLAY 0.617021 (-1775 1200);
PAINT SKYBLUE (-1775 1200);
FORCEPROP 1 LAST LOCATION R3M6
J 0
(-1775 1350);
DISPLAY 0.617021 (-1775 1350);
PAINT AQUA (-1775 1350);
FORCEPROP 1 LAST PACK_TYPE 0402
J 0
(-1650 1200);
DISPLAY 0.617021 (-1650 1200);
PAINT SKYBLUE (-1650 1200);
FORCEPROP 1 LASTPIN (-1825 1300) $PN 1
J 0
(-1813 1312);
DISPLAY 0.787234 (-1813 1312);
PAINT ORANGE (-1813 1312);
DISPLAY INVISIBLE (-1813 1312);
FORCEPROP 2 LAST ROOM VDDQ_DEF_PWR_VR
J 0
(-1775 1400);
DISPLAY 1.361702 (-1775 1400);
PAINT ORANGE (-1775 1400);
DISPLAY INVISIBLE (-1775 1400);
FORCEPROP 1 LAST PATH I59
J 0
(-1775 1450);
DISPLAY 0.978723 (-1775 1450);
PAINT WHITE (-1775 1450);
DISPLAY INVISIBLE (-1775 1450);
FORCEPROP 2 LAST CDS_LOCATION R3M6
J 0
(-1775 1350);
DISPLAY 0.617021 (-1775 1350);
PAINT AQUA (-1775 1350);
DISPLAY INVISIBLE (-1775 1350);
FORCEPROP 2 LAST CDS_LIB mstr_discrete
J 0
(-1725 1300);
PAINT ORANGE (-1725 1300);
DISPLAY INVISIBLE (-1725 1300);
FORCEPROP 1 LASTPIN (-1625 1300) $PN 2
J 0
(-1663 1312);
DISPLAY 0.787234 (-1663 1312);
PAINT ORANGE (-1663 1312);
DISPLAY INVISIBLE (-1663 1312);
FORCEPROP 2 LAST $SEC 1
J 0
(-1775 1500);
PAINT MONO (-1775 1500);
DISPLAY INVISIBLE (-1775 1500);
FORCEPROP 2 LAST CDS_SEC 1
J 0
(-1775 1500);
PAINT MONO (-1775 1500);
DISPLAY INVISIBLE (-1775 1500);
FORCEADD PVCCIO_CPU0..1
(3700 3450);
FORCEPROP 3 LASTPIN (3700 3400) SIG_NAME PVCCIO_CPU0\g
J 0
(3710 3410);
DISPLAY 0.659574 (3710 3410);
PAINT MONO (3710 3410);
DISPLAY INVISIBLE (3710 3410);
FORCEPROP 1 LAST HDL_POWER PVCCIO_CPU0
J 1
(3700 3500);
DISPLAY 0.872340 (3700 3500);
PAINT GREEN (3700 3500);
DISPLAY INVISIBLE (3700 3500);
FORCEPROP 1 LAST PATH I6
J 0
(3750 3475);
DISPLAY 0.872340 (3750 3475);
PAINT AQUA (3750 3475);
DISPLAY INVISIBLE (3750 3475);
FORCEPROP 1 LAST BODY_TYPE PLUMBING
J 0
(3655 3407);
DISPLAY 0.340426 (3655 3407);
PAINT GREEN (3655 3407);
DISPLAY INVISIBLE (3655 3407);
FORCEPROP 2 LAST CDS_LIB mstr_symbols
J 0
(3700 3450);
PAINT ORANGE (3700 3450);
DISPLAY INVISIBLE (3700 3450);
FORCEPROP 1 LAST VOLTAGE 1.1V
J 0
(3655 3407);
DISPLAY 0.340426 (3655 3407);
PAINT SKYBLUE (3655 3407);
DISPLAY INVISIBLE (3655 3407);
FORCEADD RES..1
(-1750 975);
FORCEPROP 1 LASTPIN (-1850 975) $PN 1
J 0
(-1838 987);
DISPLAY 0.617021 (-1838 987);
PAINT ORANGE (-1838 987);
FORCEPROP 1 LAST VALUE 10.0
J 2
(-1850 875);
DISPLAY 0.617021 (-1850 875);
PAINT SKYBLUE (-1850 875);
FORCEPROP 1 LAST WATTAGE 1/16W
J 2
(-1750 825);
DISPLAY 0.617021 (-1750 825);
PAINT SKYBLUE (-1750 825);
FORCEPROP 1 LAST TOLERANCE 1%
J 0
(-1825 875);
DISPLAY 0.617021 (-1825 875);
PAINT SKYBLUE (-1825 875);
FORCEPROP 1 LAST PART_NUMBER G21796-066
J 0
(-1900 925);
DISPLAY 0.617021 (-1900 925);
PAINT BLUE (-1900 925);
FORCEPROP 1 LASTPIN (-1650 975) $PN 2
J 0
(-1688 987);
DISPLAY 0.617021 (-1688 987);
PAINT ORANGE (-1688 987);
FORCEPROP 1 LAST MATERIAL CHIP
J 0
(-1725 825);
DISPLAY 0.617021 (-1725 825);
PAINT SKYBLUE (-1725 825);
FORCEPROP 1 LAST PACK_TYPE 0402
J 0
(-1725 875);
DISPLAY 0.617021 (-1725 875);
PAINT SKYBLUE (-1725 875);
FORCEPROP 1 LAST LOCATION R7A7
J 0
(-1800 1025);
DISPLAY 0.617021 (-1800 1025);
PAINT AQUA (-1800 1025);
FORCEPROP 2 LAST CDS_LIB mstr_discrete
J 0
(-1750 975);
PAINT ORANGE (-1750 975);
DISPLAY INVISIBLE (-1750 975);
FORCEPROP 1 LAST PATH I60
J 0
(-1800 1125);
DISPLAY 0.978723 (-1800 1125);
PAINT WHITE (-1800 1125);
DISPLAY INVISIBLE (-1800 1125);
FORCEPROP 2 LAST CDS_LOCATION R7A7
J 0
(-1800 1025);
DISPLAY 0.617021 (-1800 1025);
PAINT AQUA (-1800 1025);
DISPLAY INVISIBLE (-1800 1025);
FORCEPROP 2 LAST SEC_TYPE 0402
J 0
(-1800 1200);
DISPLAY 1.021277 (-1800 1200);
PAINT ORANGE (-1800 1200);
DISPLAY INVISIBLE (-1800 1200);
FORCEPROP 2 LAST SEC 1
J 0
(-1800 1200);
DISPLAY 0.680851 (-1800 1200);
PAINT MONO (-1800 1200);
DISPLAY INVISIBLE (-1800 1200);
FORCEPROP 2 LAST ROOM VDDQ_DEF_PWR_VR
J 0
(-1675 1075);
DISPLAY 1.361702 (-1675 1075);
PAINT ORANGE (-1675 1075);
DISPLAY INVISIBLE (-1675 1075);
FORCEADD CAP..1
(-1475 825);
FORCEPROP 1 LASTPIN (-1475 725) $PN 2
J 0
(-1465 705);
DISPLAY 0.617021 (-1465 705);
PAINT ORANGE (-1465 705);
FORCEPROP 1 LASTPIN (-1475 925) $PN 1
J 0
(-1465 905);
DISPLAY 0.617021 (-1465 905);
PAINT ORANGE (-1465 905);
FORCEPROP 1 LAST VOLTAGE 50V
J 0
(-1425 825);
DISPLAY 0.617021 (-1425 825);
PAINT SKYBLUE (-1425 825);
FORCEPROP 1 LAST MATERIAL X7R
J 0
(-1300 825);
DISPLAY 0.617021 (-1300 825);
PAINT SKYBLUE (-1300 825);
FORCEPROP 1 LAST PACK_TYPE 0402LF
J 0
(-1425 725);
DISPLAY 0.617021 (-1425 725);
PAINT SKYBLUE (-1425 725);
FORCEPROP 1 LAST VALUE 220PF
J 0
(-1425 875);
DISPLAY 0.617021 (-1425 875);
PAINT SKYBLUE (-1425 875);
FORCEPROP 1 LAST PART_NUMBER A36096-050
J 0
(-1425 775);
DISPLAY 0.617021 (-1425 775);
PAINT BLUE (-1425 775);
FORCEPROP 1 LAST LOCATION C7A28
J 0
(-1425 925);
DISPLAY 0.617021 (-1425 925);
PAINT AQUA (-1425 925);
FORCEPROP 1 LAST TOLERANCE 10%
J 0
(-1250 875);
DISPLAY 0.617021 (-1250 875);
PAINT SKYBLUE (-1250 875);
FORCEPROP 2 LAST CDS_LIB mstr_discrete
J 0
(-1475 825);
PAINT ORANGE (-1475 825);
DISPLAY INVISIBLE (-1475 825);
FORCEPROP 2 LAST CDS_LOCATION C7A28
J 0
(-1425 925);
DISPLAY 0.617021 (-1425 925);
PAINT AQUA (-1425 925);
DISPLAY INVISIBLE (-1425 925);
FORCEPROP 1 LAST PATH I61
J 0
(-1425 975);
DISPLAY 0.978723 (-1425 975);
PAINT WHITE (-1425 975);
DISPLAY INVISIBLE (-1425 975);
FORCEPROP 2 LAST ROOM VDDQ_DEF_PWR_VR
J 0
(-1425 975);
DISPLAY 1.361702 (-1425 975);
PAINT ORANGE (-1425 975);
DISPLAY INVISIBLE (-1425 975);
FORCEPROP 2 LAST SEC 1
J 0
(-1425 1050);
DISPLAY 0.680851 (-1425 1050);
PAINT MONO (-1425 1050);
DISPLAY INVISIBLE (-1425 1050);
FORCEPROP 2 LAST SEC_TYPE 0402LF
J 0
(-1425 1050);
DISPLAY 1.021277 (-1425 1050);
PAINT ORANGE (-1425 1050);
DISPLAY INVISIBLE (-1425 1050);
FORCEADD OFFPAGE..2
R 2
(-2350 3375);
FORCEPROP 2 LAST $XR0 218 
J 0
(-2635 3375);
DISPLAY 0.638298 (-2635 3375);
PAINT MONO (-2635 3375);
FORCEPROP 2 LAST PATH I62
J 0
(-2625 3425);
DISPLAY 1.021277 (-2625 3425);
PAINT ORANGE (-2625 3425);
DISPLAY INVISIBLE (-2625 3425);
FORCEPROP 1 LAST OFFPAGE TRUE
J 2
(-2675 3250);
DISPLAY 1.170213 (-2675 3250);
PAINT GREEN (-2675 3250);
DISPLAY INVISIBLE (-2675 3250);
FORCEPROP 2 LAST ROOM VDDQ_DEF_PWR_VR
J 0
(-2900 3450);
DISPLAY 1.361702 (-2900 3450);
PAINT ORANGE (-2900 3450);
DISPLAY INVISIBLE (-2900 3450);
FORCEPROP 1 LAST COMMENT_BODY TRUE
J 2
(-2305 3280);
DISPLAY 1.170213 (-2305 3280);
PAINT GREEN (-2305 3280);
DISPLAY INVISIBLE (-2305 3280);
FORCEPROP 2 LAST CDS_LIB mstr_standard
J 2
(-2350 3375);
PAINT ORANGE (-2350 3375);
DISPLAY INVISIBLE (-2350 3375);
FORCEADD OFFPAGE..1
(-2325 2475);
FORCEPROP 2 LAST $XR0 218 
J 0
(-2577 2475);
DISPLAY 0.638298 (-2577 2475);
PAINT MONO (-2577 2475);
FORCEPROP 2 LAST PATH I63
J 0
(-2575 2525);
DISPLAY 1.021277 (-2575 2525);
PAINT ORANGE (-2575 2525);
DISPLAY INVISIBLE (-2575 2525);
FORCEPROP 2 LAST ROOM VDDQ_DEF_PWR_VR
J 0
(-2875 2550);
DISPLAY 1.361702 (-2875 2550);
PAINT ORANGE (-2875 2550);
DISPLAY INVISIBLE (-2875 2550);
FORCEPROP 2 LAST CDS_LIB mstr_standard
J 0
(-2325 2475);
PAINT ORANGE (-2325 2475);
DISPLAY INVISIBLE (-2325 2475);
FORCEPROP 1 LAST COMMENT_BODY TRUE
J 0
(-2200 2375);
DISPLAY 1.170213 (-2200 2375);
PAINT GREEN (-2200 2375);
DISPLAY INVISIBLE (-2200 2375);
FORCEPROP 1 LAST OFFPAGE TRUE
J 0
(-2000 2350);
DISPLAY 1.170213 (-2000 2350);
PAINT GREEN (-2000 2350);
DISPLAY INVISIBLE (-2000 2350);
FORCEADD OFFPAGE..1
(-2375 2825);
FORCEPROP 2 LAST $XR0 21 
J 0
(-2596 2825);
DISPLAY 0.638298 (-2596 2825);
PAINT MONO (-2596 2825);
FORCEPROP 2 LAST $XR1 194 
J 0
(-2716 2825);
DISPLAY 0.638298 (-2716 2825);
PAINT MONO (-2716 2825);
FORCEPROP 2 LAST $XR2 215 
J 0
(-2716 2789);
DISPLAY 0.638298 (-2716 2789);
PAINT MONO (-2716 2789);
FORCEPROP 2 LAST PATH I64
J 0
(-2575 2875);
DISPLAY 1.021277 (-2575 2875);
PAINT ORANGE (-2575 2875);
DISPLAY INVISIBLE (-2575 2875);
FORCEPROP 2 LAST ROOM VDDQ_DEF_PWR_VR
J 0
(-2925 2900);
DISPLAY 1.361702 (-2925 2900);
PAINT ORANGE (-2925 2900);
DISPLAY INVISIBLE (-2925 2900);
FORCEPROP 2 LAST CDS_LIB mstr_standard
J 0
(-2375 2825);
PAINT ORANGE (-2375 2825);
DISPLAY INVISIBLE (-2375 2825);
FORCEPROP 1 LAST COMMENT_BODY TRUE
J 0
(-2250 2725);
DISPLAY 1.170213 (-2250 2725);
PAINT GREEN (-2250 2725);
DISPLAY INVISIBLE (-2250 2725);
FORCEPROP 1 LAST OFFPAGE TRUE
J 0
(-2050 2700);
DISPLAY 1.170213 (-2050 2700);
PAINT GREEN (-2050 2700);
DISPLAY INVISIBLE (-2050 2700);
FORCEADD OFFPAGE..1
(-2350 2150);
FORCEPROP 2 LAST $XR0 219 
J 0
(-2602 2150);
DISPLAY 0.638298 (-2602 2150);
PAINT MONO (-2602 2150);
FORCEPROP 2 LAST PATH I65
J 0
(-2600 2200);
DISPLAY 1.021277 (-2600 2200);
PAINT ORANGE (-2600 2200);
DISPLAY INVISIBLE (-2600 2200);
FORCEPROP 2 LAST ROOM VDDQ_DEF_PWR_VR
J 0
(-2900 2225);
DISPLAY 1.361702 (-2900 2225);
PAINT ORANGE (-2900 2225);
DISPLAY INVISIBLE (-2900 2225);
FORCEPROP 2 LAST CDS_LIB mstr_standard
J 0
(-2350 2150);
PAINT ORANGE (-2350 2150);
DISPLAY INVISIBLE (-2350 2150);
FORCEPROP 1 LAST COMMENT_BODY TRUE
J 0
(-2225 2050);
DISPLAY 1.170213 (-2225 2050);
PAINT GREEN (-2225 2050);
DISPLAY INVISIBLE (-2225 2050);
FORCEPROP 1 LAST OFFPAGE TRUE
J 0
(-2025 2025);
DISPLAY 1.170213 (-2025 2025);
PAINT GREEN (-2025 2025);
DISPLAY INVISIBLE (-2025 2025);
FORCEADD OFFPAGE..1
(-2350 2100);
FORCEPROP 2 LAST $XR0 219 
J 0
(-2602 2100);
DISPLAY 0.638298 (-2602 2100);
PAINT MONO (-2602 2100);
FORCEPROP 1 LAST COMMENT_BODY TRUE
J 0
(-2225 2000);
DISPLAY 1.170213 (-2225 2000);
PAINT GREEN (-2225 2000);
DISPLAY INVISIBLE (-2225 2000);
FORCEPROP 2 LAST PATH I66
J 0
(-2600 2150);
DISPLAY 1.021277 (-2600 2150);
PAINT ORANGE (-2600 2150);
DISPLAY INVISIBLE (-2600 2150);
FORCEPROP 2 LAST ROOM VDDQ_DEF_PWR_VR
J 0
(-2900 2175);
DISPLAY 1.361702 (-2900 2175);
PAINT ORANGE (-2900 2175);
DISPLAY INVISIBLE (-2900 2175);
FORCEPROP 2 LAST CDS_LIB mstr_standard
J 0
(-2350 2100);
PAINT ORANGE (-2350 2100);
DISPLAY INVISIBLE (-2350 2100);
FORCEPROP 1 LAST OFFPAGE TRUE
J 0
(-2025 1975);
DISPLAY 1.170213 (-2025 1975);
PAINT GREEN (-2025 1975);
DISPLAY INVISIBLE (-2025 1975);
FORCEADD OFFPAGE..1
(-2350 1950);
FORCEPROP 2 LAST $XR0 219 
J 0
(-2602 1950);
DISPLAY 0.638298 (-2602 1950);
PAINT MONO (-2602 1950);
FORCEPROP 2 LAST PATH I67
J 0
(-2600 2000);
DISPLAY 1.021277 (-2600 2000);
PAINT ORANGE (-2600 2000);
DISPLAY INVISIBLE (-2600 2000);
FORCEPROP 2 LAST CDS_LIB mstr_standard
J 0
(-2350 1950);
PAINT ORANGE (-2350 1950);
DISPLAY INVISIBLE (-2350 1950);
FORCEPROP 1 LAST COMMENT_BODY TRUE
J 0
(-2225 1850);
DISPLAY 1.170213 (-2225 1850);
PAINT GREEN (-2225 1850);
DISPLAY INVISIBLE (-2225 1850);
FORCEPROP 2 LAST ROOM VDDQ_DEF_PWR_VR
J 0
(-2900 2025);
DISPLAY 1.361702 (-2900 2025);
PAINT ORANGE (-2900 2025);
DISPLAY INVISIBLE (-2900 2025);
FORCEPROP 1 LAST OFFPAGE TRUE
J 0
(-2025 1825);
DISPLAY 1.170213 (-2025 1825);
PAINT GREEN (-2025 1825);
DISPLAY INVISIBLE (-2025 1825);
FORCEADD OFFPAGE..1
(-2350 1900);
FORCEPROP 2 LAST $XR0 219 
J 0
(-2602 1900);
DISPLAY 0.638298 (-2602 1900);
PAINT MONO (-2602 1900);
FORCEPROP 2 LAST PATH I68
J 0
(-2600 1950);
DISPLAY 1.021277 (-2600 1950);
PAINT ORANGE (-2600 1950);
DISPLAY INVISIBLE (-2600 1950);
FORCEPROP 2 LAST ROOM VDDQ_DEF_PWR_VR
J 0
(-2900 1975);
DISPLAY 1.361702 (-2900 1975);
PAINT ORANGE (-2900 1975);
DISPLAY INVISIBLE (-2900 1975);
FORCEPROP 2 LAST CDS_LIB mstr_standard
J 0
(-2350 1900);
PAINT ORANGE (-2350 1900);
DISPLAY INVISIBLE (-2350 1900);
FORCEPROP 1 LAST COMMENT_BODY TRUE
J 0
(-2225 1800);
DISPLAY 1.170213 (-2225 1800);
PAINT GREEN (-2225 1800);
DISPLAY INVISIBLE (-2225 1800);
FORCEPROP 1 LAST OFFPAGE TRUE
J 0
(-2025 1775);
DISPLAY 1.170213 (-2025 1775);
PAINT GREEN (-2025 1775);
DISPLAY INVISIBLE (-2025 1775);
FORCEADD OFFPAGE..1
(-2350 1700);
FORCEPROP 2 LAST $XR0 197 
J 0
(-2602 1700);
DISPLAY 0.638298 (-2602 1700);
PAINT MONO (-2602 1700);
FORCEPROP 2 LAST PATH I69
J 0
(-2600 1750);
DISPLAY 1.021277 (-2600 1750);
PAINT ORANGE (-2600 1750);
DISPLAY INVISIBLE (-2600 1750);
FORCEPROP 2 LAST ROOM VDDQ_DEF_PWR_VR
J 0
(-2900 1775);
DISPLAY 1.361702 (-2900 1775);
PAINT ORANGE (-2900 1775);
DISPLAY INVISIBLE (-2900 1775);
FORCEPROP 2 LAST CDS_LIB mstr_standard
J 0
(-2350 1700);
PAINT ORANGE (-2350 1700);
DISPLAY INVISIBLE (-2350 1700);
FORCEPROP 1 LAST COMMENT_BODY TRUE
J 0
(-2225 1600);
DISPLAY 1.170213 (-2225 1600);
PAINT GREEN (-2225 1600);
DISPLAY INVISIBLE (-2225 1600);
FORCEPROP 1 LAST OFFPAGE TRUE
J 0
(-2025 1575);
DISPLAY 1.170213 (-2025 1575);
PAINT GREEN (-2025 1575);
DISPLAY INVISIBLE (-2025 1575);
FORCEADD RES..2
(3700 2725);
FORCEPROP 1 LAST PACK_TYPE 0402
J 0
(3740 2550);
DISPLAY 0.617021 (3740 2550);
PAINT SKYBLUE (3740 2550);
FORCEPROP 1 LASTPIN (3700 2825) $PN 1
J 0
(3705 2787);
DISPLAY 0.617021 (3705 2787);
PAINT ORANGE (3705 2787);
FORCEPROP 1 LASTPIN (3700 2625) $PN 2
J 0
(3705 2635);
DISPLAY 0.617021 (3705 2635);
PAINT ORANGE (3705 2635);
FORCEPROP 1 LAST TOLERANCE 1%
J 0
(3745 2750);
DISPLAY 0.617021 (3745 2750);
PAINT SKYBLUE (3745 2750);
FORCEPROP 1 LAST WATTAGE 1/16W
J 0
(3740 2700);
DISPLAY 0.617021 (3740 2700);
PAINT SKYBLUE (3740 2700);
FORCEPROP 1 LAST VALUE 100.0
J 0
(3745 2800);
DISPLAY 0.617021 (3745 2800);
PAINT SKYBLUE (3745 2800);
FORCEPROP 1 LAST PART_NUMBER G21796-017
J 0
(3740 2600);
DISPLAY 0.617021 (3740 2600);
PAINT BLUE (3740 2600);
FORCEPROP 1 LAST LOCATION R3L11
J 0
(3745 2850);
DISPLAY 0.617021 (3745 2850);
PAINT AQUA (3745 2850);
FORCEPROP 1 LAST MATERIAL EMPTY
J 0
(3740 2650);
DISPLAY 0.617021 (3740 2650);
PAINT RED (3740 2650);
FORCEPROP 2 LAST CDS_LIB mstr_discrete
J 0
(3700 2725);
PAINT ORANGE (3700 2725);
DISPLAY INVISIBLE (3700 2725);
FORCEPROP 2 LAST ROOM VDDQ_DEF_PWR_VR
J 0
(3750 2900);
DISPLAY 1.361702 (3750 2900);
PAINT ORANGE (3750 2900);
DISPLAY INVISIBLE (3750 2900);
FORCEPROP 1 LAST PATH I7
J 0
(3750 2900);
DISPLAY 0.978723 (3750 2900);
PAINT WHITE (3750 2900);
DISPLAY INVISIBLE (3750 2900);
FORCEPROP 2 LAST CDS_LOCATION R3L11
J 0
(3745 2850);
DISPLAY 0.617021 (3745 2850);
PAINT AQUA (3745 2850);
DISPLAY INVISIBLE (3745 2850);
FORCEPROP 2 LAST SEC 1
J 0
(3750 2975);
DISPLAY 0.680851 (3750 2975);
PAINT MONO (3750 2975);
DISPLAY INVISIBLE (3750 2975);
FORCEPROP 2 LAST SEC_TYPE 0402
J 0
(3750 2975);
DISPLAY 1.021277 (3750 2975);
PAINT ORANGE (3750 2975);
DISPLAY INVISIBLE (3750 2975);
FORCEADD OFFPAGE..1
(-2350 1600);
FORCEPROP 2 LAST $XR0 219 
J 0
(-2602 1600);
DISPLAY 0.638298 (-2602 1600);
PAINT MONO (-2602 1600);
FORCEPROP 2 LAST PATH I70
J 0
(-2600 1650);
DISPLAY 1.021277 (-2600 1650);
PAINT ORANGE (-2600 1650);
DISPLAY INVISIBLE (-2600 1650);
FORCEPROP 2 LAST ROOM VDDQ_DEF_PWR_VR
J 0
(-2900 1675);
DISPLAY 1.361702 (-2900 1675);
PAINT ORANGE (-2900 1675);
DISPLAY INVISIBLE (-2900 1675);
FORCEPROP 1 LAST COMMENT_BODY TRUE
J 0
(-2225 1500);
DISPLAY 1.170213 (-2225 1500);
PAINT GREEN (-2225 1500);
DISPLAY INVISIBLE (-2225 1500);
FORCEPROP 2 LAST CDS_LIB mstr_standard
J 0
(-2350 1600);
PAINT ORANGE (-2350 1600);
DISPLAY INVISIBLE (-2350 1600);
FORCEPROP 1 LAST OFFPAGE TRUE
J 0
(-2025 1475);
DISPLAY 1.170213 (-2025 1475);
PAINT GREEN (-2025 1475);
DISPLAY INVISIBLE (-2025 1475);
FORCEADD OFFPAGE..1
(-2350 1750);
FORCEPROP 2 LAST $XR0 218 
J 0
(-2602 1750);
DISPLAY 0.638298 (-2602 1750);
PAINT MONO (-2602 1750);
FORCEPROP 2 LAST PATH I71
J 0
(-2600 1800);
DISPLAY 1.021277 (-2600 1800);
PAINT ORANGE (-2600 1800);
DISPLAY INVISIBLE (-2600 1800);
FORCEPROP 2 LAST ROOM VDDQ_DEF_PWR_VR
J 0
(-2900 1825);
DISPLAY 1.361702 (-2900 1825);
PAINT ORANGE (-2900 1825);
DISPLAY INVISIBLE (-2900 1825);
FORCEPROP 2 LAST CDS_LIB mstr_standard
J 0
(-2350 1750);
PAINT ORANGE (-2350 1750);
DISPLAY INVISIBLE (-2350 1750);
FORCEPROP 1 LAST COMMENT_BODY TRUE
J 0
(-2225 1650);
DISPLAY 1.170213 (-2225 1650);
PAINT GREEN (-2225 1650);
DISPLAY INVISIBLE (-2225 1650);
FORCEPROP 1 LAST OFFPAGE TRUE
J 0
(-2025 1625);
DISPLAY 1.170213 (-2025 1625);
PAINT GREEN (-2025 1625);
DISPLAY INVISIBLE (-2025 1625);
FORCEADD OFFPAGE..1
(-2375 975);
FORCEPROP 2 LAST $XR0 220 
J 0
(-2627 975);
DISPLAY 0.638298 (-2627 975);
PAINT MONO (-2627 975);
FORCEPROP 2 LAST CDS_LIB mstr_standard
J 0
(-2375 975);
PAINT ORANGE (-2375 975);
DISPLAY INVISIBLE (-2375 975);
FORCEPROP 1 LAST COMMENT_BODY TRUE
J 0
(-2250 875);
DISPLAY 1.170213 (-2250 875);
PAINT GREEN (-2250 875);
DISPLAY INVISIBLE (-2250 875);
FORCEPROP 1 LAST OFFPAGE TRUE
J 0
(-2050 850);
DISPLAY 1.170213 (-2050 850);
PAINT GREEN (-2050 850);
DISPLAY INVISIBLE (-2050 850);
FORCEPROP 2 LAST PATH I72
J 0
(-2625 1025);
DISPLAY 1.021277 (-2625 1025);
PAINT ORANGE (-2625 1025);
DISPLAY INVISIBLE (-2625 1025);
FORCEPROP 2 LAST ROOM VDDQ_DEF_PWR_VR
J 0
(-2925 1050);
DISPLAY 1.361702 (-2925 1050);
PAINT ORANGE (-2925 1050);
DISPLAY INVISIBLE (-2925 1050);
FORCEADD OFFPAGE..1
(-2350 1300);
FORCEPROP 2 LAST $XR0 191 
J 0
(-2602 1300);
DISPLAY 0.638298 (-2602 1300);
PAINT MONO (-2602 1300);
FORCEPROP 2 LAST PATH I73
J 0
(-2600 1350);
DISPLAY 1.021277 (-2600 1350);
PAINT ORANGE (-2600 1350);
DISPLAY INVISIBLE (-2600 1350);
FORCEPROP 2 LAST ROOM VDDQ_DEF_PWR_VR
J 0
(-2900 1375);
DISPLAY 1.361702 (-2900 1375);
PAINT ORANGE (-2900 1375);
DISPLAY INVISIBLE (-2900 1375);
FORCEPROP 2 LAST CDS_LIB mstr_standard
J 0
(-2350 1300);
PAINT ORANGE (-2350 1300);
DISPLAY INVISIBLE (-2350 1300);
FORCEPROP 1 LAST COMMENT_BODY TRUE
J 0
(-2225 1200);
DISPLAY 1.170213 (-2225 1200);
PAINT GREEN (-2225 1200);
DISPLAY INVISIBLE (-2225 1200);
FORCEPROP 1 LAST OFFPAGE TRUE
J 0
(-2025 1175);
DISPLAY 1.170213 (-2025 1175);
PAINT GREEN (-2025 1175);
DISPLAY INVISIBLE (-2025 1175);
FORCEADD OFFPAGE..1
(-2350 700);
FORCEPROP 2 LAST $XR0 220 
J 0
(-2602 700);
DISPLAY 0.638298 (-2602 700);
PAINT MONO (-2602 700);
FORCEPROP 2 LAST PATH I74
J 0
(-2600 750);
DISPLAY 1.021277 (-2600 750);
PAINT ORANGE (-2600 750);
DISPLAY INVISIBLE (-2600 750);
FORCEPROP 2 LAST ROOM VDDQ_DEF_PWR_VR
J 0
(-2900 775);
DISPLAY 1.361702 (-2900 775);
PAINT ORANGE (-2900 775);
DISPLAY INVISIBLE (-2900 775);
FORCEPROP 2 LAST CDS_LIB mstr_standard
J 0
(-2350 700);
PAINT ORANGE (-2350 700);
DISPLAY INVISIBLE (-2350 700);
FORCEPROP 1 LAST COMMENT_BODY TRUE
J 0
(-2225 600);
DISPLAY 1.170213 (-2225 600);
PAINT GREEN (-2225 600);
DISPLAY INVISIBLE (-2225 600);
FORCEPROP 1 LAST OFFPAGE TRUE
J 0
(-2025 575);
DISPLAY 1.170213 (-2025 575);
PAINT GREEN (-2025 575);
DISPLAY INVISIBLE (-2025 575);
FORCEADD PXM1310B..2
(1325 1600);
FORCEPROP 2 LASTPIN (875 750) $PN 33
J 2
(865 760);
DISPLAY 0.617021 (865 760);
PAINT ORANGE (865 760);
FORCEPROP 2 LASTPIN (875 800) $PN 36
J 2
(865 810);
DISPLAY 0.617021 (865 810);
PAINT ORANGE (865 810);
FORCEPROP 2 LASTPIN (875 900) $PN 32
J 2
(865 910);
DISPLAY 0.617021 (865 910);
PAINT ORANGE (865 910);
FORCEPROP 2 LASTPIN (875 950) $PN 31
J 2
(865 960);
DISPLAY 0.617021 (865 960);
PAINT ORANGE (865 960);
FORCEPROP 2 LASTPIN (875 1200) $PN 20
J 2
(865 1210);
DISPLAY 0.617021 (865 1210);
PAINT ORANGE (865 1210);
FORCEPROP 2 LASTPIN (875 1150) $PN 30
J 2
(865 1160);
DISPLAY 0.617021 (865 1160);
PAINT ORANGE (865 1160);
FORCEPROP 2 LASTPIN (875 1050) $PN 8
J 2
(865 1060);
DISPLAY 0.617021 (865 1060);
PAINT ORANGE (865 1060);
FORCEPROP 2 LASTPIN (875 1300) $PN 10
J 2
(865 1310);
DISPLAY 0.617021 (865 1310);
PAINT ORANGE (865 1310);
FORCEPROP 2 LASTPIN (875 1450) $PN 19
J 2
(865 1460);
DISPLAY 0.617021 (865 1460);
PAINT ORANGE (865 1460);
FORCEPROP 2 LASTPIN (875 1400) $PN 29
J 2
(865 1410);
DISPLAY 0.617021 (865 1410);
PAINT ORANGE (865 1410);
FORCEPROP 2 LASTPIN (875 1600) $PN 35
J 2
(865 1610);
DISPLAY 0.617021 (865 1610);
PAINT ORANGE (865 1610);
FORCEPROP 2 LASTPIN (875 1550) $PN 34
J 2
(865 1560);
DISPLAY 0.617021 (865 1560);
PAINT ORANGE (865 1560);
FORCEPROP 2 LASTPIN (875 1700) $PN 38
J 2
(865 1710);
DISPLAY 0.617021 (865 1710);
PAINT ORANGE (865 1710);
FORCEPROP 2 LASTPIN (875 1750) $PN 37
J 2
(865 1760);
DISPLAY 0.617021 (865 1760);
PAINT ORANGE (865 1760);
FORCEPROP 2 LASTPIN (875 1950) $PN 22
J 2
(865 1960);
DISPLAY 0.617021 (865 1960);
PAINT ORANGE (865 1960);
FORCEPROP 2 LASTPIN (875 1900) $PN 24
J 2
(865 1910);
DISPLAY 0.617021 (865 1910);
PAINT ORANGE (865 1910);
FORCEPROP 2 LASTPIN (875 1850) $PN 26
J 2
(865 1860);
DISPLAY 0.617021 (865 1860);
PAINT ORANGE (865 1860);
FORCEPROP 1 LAST PART_NUMBER H89186-001
J 0
(925 650);
DISPLAY 0.617021 (925 650);
PAINT BLUE (925 650);
FORCEPROP 2 LASTPIN (1775 800) $PN 27
J 0
(1785 810);
DISPLAY 0.617021 (1785 810);
PAINT ORANGE (1785 810);
FORCEPROP 2 LASTPIN (1775 900) $PN 41
J 0
(1785 910);
DISPLAY 0.617021 (1785 910);
PAINT ORANGE (1785 910);
FORCEPROP 2 LASTPIN (1775 1000) $PN 2
J 0
(1785 1010);
DISPLAY 0.617021 (1785 1010);
PAINT ORANGE (1785 1010);
FORCEPROP 2 LASTPIN (1775 1300) $PN 5
J 0
(1785 1310);
DISPLAY 0.617021 (1785 1310);
PAINT ORANGE (1785 1310);
FORCEPROP 2 LASTPIN (1775 1500) $PN 16
J 0
(1785 1510);
DISPLAY 0.617021 (1785 1510);
PAINT ORANGE (1785 1510);
FORCEPROP 2 LASTPIN (1775 1050) $PN 28
J 0
(1785 1060);
DISPLAY 0.617021 (1785 1060);
PAINT ORANGE (1785 1060);
FORCEPROP 2 LASTPIN (1775 1350) $PN 1
J 0
(1785 1360);
DISPLAY 0.617021 (1785 1360);
PAINT ORANGE (1785 1360);
FORCEPROP 2 LASTPIN (1775 1200) $PN 3
J 0
(1785 1210);
DISPLAY 0.617021 (1785 1210);
PAINT ORANGE (1785 1210);
FORCEPROP 2 LASTPIN (1775 1250) $PN 4
J 0
(1785 1260);
DISPLAY 0.617021 (1785 1260);
PAINT ORANGE (1785 1260);
FORCEPROP 2 LASTPIN (1775 1700) $PN 13
J 0
(1785 1710);
DISPLAY 0.617021 (1785 1710);
PAINT ORANGE (1785 1710);
FORCEPROP 2 LASTPIN (1775 1650) $PN 14
J 0
(1785 1660);
DISPLAY 0.617021 (1785 1660);
PAINT ORANGE (1785 1660);
FORCEPROP 2 LASTPIN (1775 1950) $PN 12
J 0
(1785 1960);
DISPLAY 0.617021 (1785 1960);
PAINT ORANGE (1785 1960);
FORCEPROP 2 LASTPIN (1775 1850) $PN 7
J 0
(1785 1860);
DISPLAY 0.617021 (1785 1860);
PAINT ORANGE (1785 1860);
FORCEPROP 2 LASTPIN (1775 1800) $PN 6
J 0
(1785 1810);
DISPLAY 0.617021 (1785 1810);
PAINT ORANGE (1785 1810);
FORCEPROP 2 LASTPIN (1775 1550) $PN 40
J 0
(1785 1560);
DISPLAY 0.617021 (1785 1560);
PAINT ORANGE (1785 1560);
FORCEPROP 2 LASTPIN (875 2050) $PN 25
J 2
(865 2060);
DISPLAY 0.617021 (865 2060);
PAINT ORANGE (865 2060);
FORCEPROP 2 LASTPIN (875 2100) $PN 23
J 2
(865 2110);
DISPLAY 0.617021 (865 2110);
PAINT ORANGE (865 2110);
FORCEPROP 2 LASTPIN (875 2150) $PN 21
J 2
(865 2160);
DISPLAY 0.617021 (865 2160);
PAINT ORANGE (865 2160);
FORCEPROP 2 LASTPIN (875 2250) $PN 15
J 2
(865 2260);
DISPLAY 0.617021 (865 2260);
PAINT ORANGE (865 2260);
FORCEPROP 2 LASTPIN (875 2350) $PN 39
J 2
(865 2360);
DISPLAY 0.617021 (865 2360);
PAINT ORANGE (865 2360);
FORCEPROP 1 LAST MATERIAL IC
J 0
(925 2525);
DISPLAY 0.617021 (925 2525);
PAINT SKYBLUE (925 2525);
FORCEPROP 1 LAST LOCATION EU7A5
J 0
(925 2575);
DISPLAY 0.617021 (925 2575);
PAINT AQUA (925 2575);
FORCEPROP 2 LASTPIN (1775 2350) $PN 9
J 0
(1785 2360);
DISPLAY 0.617021 (1785 2360);
PAINT ORANGE (1785 2360);
FORCEPROP 2 LASTPIN (1775 2050) $PN 18
J 0
(1785 2060);
DISPLAY 0.617021 (1785 2060);
PAINT ORANGE (1785 2060);
FORCEPROP 2 LASTPIN (1775 2200) $PN 17
J 0
(1785 2210);
DISPLAY 0.617021 (1785 2210);
PAINT ORANGE (1785 2210);
FORCEPROP 2 LASTPIN (1775 2250) $PN 11
J 0
(1785 2260);
DISPLAY 0.617021 (1785 2260);
PAINT ORANGE (1785 2260);
FORCEPROP 2 LAST CDS_LIB mstr_controller
J 0
(1325 1600);
PAINT ORANGE (1325 1600);
DISPLAY INVISIBLE (1325 1600);
FORCEPROP 1 LAST CDS_LMAN_SYM_OUTLINE -400,900,400,-900
J 0
(1325 1600);
DISPLAY 0.468085 (1325 1600);
PAINT GREEN (1325 1600);
DISPLAY INVISIBLE (1325 1600);
FORCEPROP 2 LAST CDS_LOCATION EU7A5
J 0
(925 2575);
PAINT WHITE (925 2575);
DISPLAY INVISIBLE (925 2575);
FORCEPROP 1 LAST PACK_TYPE QFN
J 0
(925 2625);
PAINT SKYBLUE (925 2625);
DISPLAY INVISIBLE (925 2625);
FORCEPROP 2 LAST SEC_TYPE QFN
J 0
(925 2625);
DISPLAY 1.021277 (925 2625);
PAINT ORANGE (925 2625);
DISPLAY INVISIBLE (925 2625);
FORCEPROP 2 LAST SEC 1
J 0
(925 2625);
DISPLAY 0.680851 (925 2625);
PAINT MONO (925 2625);
DISPLAY INVISIBLE (925 2625);
FORCEPROP 1 LAST PATH I75
J 0
(1425 2526);
PAINT WHITE (1425 2526);
DISPLAY INVISIBLE (1425 2526);
FORCEADD GND..1
(-800 0);
FORCEPROP 3 LASTPIN (-800 50) SIG_NAME GND\g
J 0
(-790 60);
DISPLAY 0.659574 (-790 60);
PAINT MONO (-790 60);
DISPLAY INVISIBLE (-790 60);
FORCEPROP 1 LAST VOLTAGE 0.0V
J 0
(-845 -43);
DISPLAY 0.340426 (-845 -43);
PAINT SKYBLUE (-845 -43);
DISPLAY INVISIBLE (-845 -43);
FORCEPROP 1 LAST SIZE 1B
J 0
(-725 -50);
DISPLAY 1.170213 (-725 -50);
PAINT AQUA (-725 -50);
DISPLAY INVISIBLE (-725 -50);
FORCEPROP 1 LAST BODY_TYPE PLUMBING
J 0
(-845 -43);
DISPLAY 0.340426 (-845 -43);
PAINT GREEN (-845 -43);
DISPLAY INVISIBLE (-845 -43);
FORCEPROP 1 LAST PATH I76
J 0
(-725 0);
DISPLAY 0.872340 (-725 0);
PAINT AQUA (-725 0);
DISPLAY INVISIBLE (-725 0);
FORCEPROP 2 LAST CDS_LIB mstr_symbols
J 0
(-800 0);
PAINT ORANGE (-800 0);
DISPLAY INVISIBLE (-800 0);
FORCEPROP 1 LAST HDL_POWER GND
J 0
(-800 150);
DISPLAY 1.170213 (-800 150);
PAINT GREEN (-800 150);
DISPLAY INVISIBLE (-800 150);
FORCEADD CAP_A..1
R 2
(-800 350);
FORCEPROP 1 LAST PART_NUMBER A36096-030
J 2
(-850 200);
DISPLAY 0.617021 (-850 200);
PAINT BLUE (-850 200);
FORCEPROP 1 LAST PACK_TYPE 0402V
J 2
(-850 150);
DISPLAY 0.617021 (-850 150);
PAINT SKYBLUE (-850 150);
FORCEPROP 1 LASTPIN (-800 250) $PN 2
J 2
(-810 230);
DISPLAY 0.617021 (-810 230);
PAINT ORANGE (-810 230);
FORCEPROP 1 LAST MATERIAL X7R
J 2
(-850 250);
DISPLAY 0.617021 (-850 250);
PAINT SKYBLUE (-850 250);
FORCEPROP 1 LAST VOLTAGE 16V
J 2
(-850 350);
DISPLAY 0.617021 (-850 350);
PAINT SKYBLUE (-850 350);
FORCEPROP 1 LAST TOLERANCE 10%
J 2
(-850 300);
DISPLAY 0.617021 (-850 300);
PAINT SKYBLUE (-850 300);
FORCEPROP 1 LAST VALUE 0.1UF
J 2
(-850 400);
DISPLAY 0.617021 (-850 400);
PAINT SKYBLUE (-850 400);
FORCEPROP 1 LAST LOCATION C3L31
J 2
(-850 450);
DISPLAY 0.617021 (-850 450);
PAINT AQUA (-850 450);
FORCEPROP 1 LASTPIN (-800 450) $PN 1
J 2
(-810 430);
DISPLAY 0.617021 (-810 430);
PAINT ORANGE (-810 430);
FORCEPROP 2 LAST CDS_LIB dev_discrete
J 0
(-800 350);
PAINT ORANGE (-800 350);
DISPLAY INVISIBLE (-800 350);
FORCEPROP 1 LAST PATH I77
J 2
(-850 500);
DISPLAY 0.978723 (-850 500);
PAINT WHITE (-850 500);
DISPLAY INVISIBLE (-850 500);
FORCEPROP 0 LAST ROOM VDDQ_DEF_PWR_VR
J 0
(-850 500);
DISPLAY 1.021277 (-850 500);
PAINT ORANGE (-850 500);
DISPLAY INVISIBLE (-850 500);
FORCEPROP 2 LAST CDS_SEC 1
J 0
(-850 500);
PAINT ORANGE (-850 500);
DISPLAY INVISIBLE (-850 500);
FORCEPROP 2 LAST SEC_TYPE 0402V
J 0
(-850 550);
DISPLAY 1.021277 (-850 550);
PAINT ORANGE (-850 550);
DISPLAY INVISIBLE (-850 550);
FORCEPROP 2 LAST SEC 1
J 0
(-850 550);
DISPLAY 0.680851 (-850 550);
PAINT MONO (-850 550);
DISPLAY INVISIBLE (-850 550);
FORCEADD OFFPAGE..2
(3925 2350);
FORCEPROP 2 LAST $XR0 222 
J 0
(4114 2350);
DISPLAY 0.638298 (4114 2350);
PAINT MONO (4114 2350);
FORCEPROP 2 LAST ROOM VDDQ_DEF_PWR_VR
J 0
(3500 2425);
DISPLAY 1.361702 (3500 2425);
PAINT ORANGE (3500 2425);
DISPLAY INVISIBLE (3500 2425);
FORCEPROP 1 LAST COMMENT_BODY TRUE
J 0
(3880 2255);
DISPLAY 1.170213 (3880 2255);
PAINT GREEN (3880 2255);
DISPLAY INVISIBLE (3880 2255);
FORCEPROP 2 LAST CDS_LIB mstr_standard
J 0
(3925 2350);
PAINT ORANGE (3925 2350);
DISPLAY INVISIBLE (3925 2350);
FORCEPROP 2 LAST PATH I8
J 0
(4125 2400);
DISPLAY 1.021277 (4125 2400);
PAINT ORANGE (4125 2400);
DISPLAY INVISIBLE (4125 2400);
FORCEPROP 1 LAST OFFPAGE TRUE
J 0
(4250 2225);
DISPLAY 1.170213 (4250 2225);
PAINT GREEN (4250 2225);
DISPLAY INVISIBLE (4250 2225);
FORCEADD OFFPAGE..2
(3925 2250);
FORCEPROP 2 LAST $XR0 94 
J 0
(4114 2250);
DISPLAY 0.638298 (4114 2250);
PAINT MONO (4114 2250);
FORCEPROP 2 LAST $XR1 119 
J 0
(4204 2250);
DISPLAY 0.638298 (4204 2250);
PAINT MONO (4204 2250);
FORCEPROP 2 LAST $XR2 144 
J 0
(4324 2250);
DISPLAY 0.638298 (4324 2250);
PAINT MONO (4324 2250);
FORCEPROP 2 LAST ROOM VDDQ_DEF_PWR_VR
J 0
(3500 2325);
DISPLAY 1.361702 (3500 2325);
PAINT ORANGE (3500 2325);
DISPLAY INVISIBLE (3500 2325);
FORCEPROP 1 LAST COMMENT_BODY TRUE
J 0
(3880 2155);
DISPLAY 1.170213 (3880 2155);
PAINT GREEN (3880 2155);
DISPLAY INVISIBLE (3880 2155);
FORCEPROP 2 LAST CDS_LIB mstr_standard
J 0
(3925 2250);
PAINT ORANGE (3925 2250);
DISPLAY INVISIBLE (3925 2250);
FORCEPROP 2 LAST PATH I9
J 0
(4325 2300);
DISPLAY 1.021277 (4325 2300);
PAINT ORANGE (4325 2300);
DISPLAY INVISIBLE (4325 2300);
FORCEPROP 1 LAST OFFPAGE TRUE
J 0
(4250 2125);
DISPLAY 1.170213 (4250 2125);
PAINT GREEN (4250 2125);
DISPLAY INVISIBLE (4250 2125);
FORCEADD DESIGN_NOTE..1
(725 450);
FORCEPROP 0 LAST L2 SVID ADDRESS=0X2
J 0
(530 265);
DISPLAY 1.021277 (530 265);
PAINT ORANGE (530 265);
FORCEPROP 0 LAST L1 SMBUS ADDRESS: 0X54
J 0
(525 325);
DISPLAY 1.021277 (525 325);
PAINT ORANGE (525 325);
FORCEPROP 2 LAST CDS_LIB mstr_symbols
J 0
(725 450);
PAINT ORANGE (725 450);
DISPLAY INVISIBLE (725 450);
FORCEPROP 1 LAST COMMENT_BODY TRUE
J 0
(750 550);
DISPLAY 0.978723 (750 550);
PAINT ORANGE (750 550);
DISPLAY INVISIBLE (750 550);
FORCEADD DNS..2
(3705 2720);
PAINT RED (3705 2720);
FORCEPROP 1 LAST COMMENT_BODY TRUE
R 1
J 0
(3780 2495);
DISPLAY 0.872340 (3780 2495);
PAINT GREEN (3780 2495);
DISPLAY INVISIBLE (3780 2495);
FORCEPROP 2 LAST CDS_LIB mstr_misc
J 0
(3705 2720);
PAINT ORANGE (3705 2720);
DISPLAY INVISIBLE (3705 2720);
FORCEADD DNS..2
(30 3320);
PAINT RED (30 3320);
FORCEPROP 1 LAST COMMENT_BODY TRUE
R 1
J 0
(105 3095);
DISPLAY 0.872340 (105 3095);
PAINT GREEN (105 3095);
DISPLAY INVISIBLE (105 3095);
FORCEPROP 2 LAST CDS_LIB mstr_misc
J 0
(30 3320);
PAINT ORANGE (30 3320);
DISPLAY INVISIBLE (30 3320);
FORCEADD DNS..2
(2655 2720);
PAINT RED (2655 2720);
FORCEPROP 1 LAST COMMENT_BODY TRUE
R 1
J 0
(2730 2495);
DISPLAY 0.872340 (2730 2495);
PAINT GREEN (2730 2495);
DISPLAY INVISIBLE (2730 2495);
FORCEPROP 2 LAST CDS_LIB mstr_misc
J 0
(2655 2720);
PAINT ORANGE (2655 2720);
DISPLAY INVISIBLE (2655 2720);
FORCEADD DESIGN_NOTE..1
(4150 3725);
PAINT PURPLE (4150 3725);
FORCEPROP 0 LAST L2 SVID ADDRESS=0X2
J 0
(3980 3540);
DISPLAY 1.021277 (3980 3540);
PAINT ORANGE (3980 3540);
FORCEPROP 0 LAST L1 SMBUS ADDRESS 0X54
J 0
(3975 3600);
PAINT VIOLET (3975 3600);
FORCEPROP 2 LAST ROOM VDDQ_DEF_PWR_VR
J 0
(3950 3675);
PAINT MONO (3950 3675);
DISPLAY INVISIBLE (3950 3675);
FORCEPROP 2 LAST BOM_COST VDDQ_DEF_VR
J 0
(3950 3675);
PAINT MONO (3950 3675);
DISPLAY INVISIBLE (3950 3675);
FORCEPROP 1 LAST COMMENT_BODY TRUE
J 0
(4175 3825);
DISPLAY 1.319149 (4175 3825);
PAINT GREEN (4175 3825);
DISPLAY INVISIBLE (4175 3825);
FORCEPROP 2 LAST CDS_LIB mstr_symbols
J 0
(4150 3725);
PAINT MONO (4150 3725);
DISPLAY INVISIBLE (4150 3725);
FORCEADD INTEL_CORP_BPAGE..1
(5250 -875);
FORCEPROP 1 LAST CDS_CON_LAST_MODIFIED Tue Dec 01 11:52:25 2015
J 0
(3825 -550);
DISPLAY 0.744681 (3825 -550);
PAINT GREEN (3825 -550);
DISPLAY INVISIBLE (3825 -550);
FORCEPROP 1 LAST CUSTOM_TXT_CDS <CURRENT_DESIGN_SHEET> OF <TOTAL_DESIGN_SHEETS>
J 0
(4750 -850);
PAINT GREEN (4750 -850);
FORCEPROP 1 LAST CUSTOM_TXT_CDS <CON_LAST_MODIFIED>
J 0
(3325 -525);
PAINT GREEN (3325 -525);
FORCEPROP 2 LAST CUSTOM_TXT_CDS <XR_PAGE_TITLE>
J 0
(-2640 4375);
DISPLAY 0.638298 (-2640 4375);
PAINT PINK (-2640 4375);
DISPLAY INVISIBLE (-2640 4375);
FORCEPROP 1 LAST SCH_TITLE VDDQ DEF_VR (1 OF 3)
J 0
(-2725 -850);
DISPLAY 1.212766 (-2725 -850);
PAINT ORANGE (-2725 -850);
FORCEPROP 1 LAST SCH_ADDRESS1 2200 MISSION COLLEGE BLVD.
J 0
(1275 -750);
DISPLAY 0.617021 (1275 -750);
PAINT GREEN (1275 -750);
FORCEPROP 1 LAST SCH_ADDRESS2 P.O. BOX 58119
J 0
(1275 -800);
DISPLAY 0.617021 (1275 -800);
PAINT GREEN (1275 -800);
FORCEPROP 1 LAST SCH_ADDRESS3 SANTA CLARA, CA 95052-8119
J 0
(1275 -850);
DISPLAY 0.617021 (1275 -850);
PAINT GREEN (1275 -850);
FORCEPROP 1 LAST SCH_NUMBER H4694802
J 0
(3950 -725);
DISPLAY 1.212766 (3950 -725);
PAINT YELLOW (3950 -725);
FORCEPROP 1 LAST SCH_DEPT BESD
J 1
(800 -775);
DISPLAY 1.212766 (800 -775);
PAINT YELLOW (800 -775);
FORCEPROP 1 LAST SCH_REV 2.420
J 0
(5000 -725);
DISPLAY 0.978723 (5000 -725);
PAINT YELLOW (5000 -725);
FORCEPROP 2 LAST PAGE_BORDER TRUE
J 0
(-2640 4375);
DISPLAY 0.638298 (-2640 4375);
PAINT PINK (-2640 4375);
DISPLAY INVISIBLE (-2640 4375);
FORCEPROP 1 LAST COMMENT_BODY TRUE
J 0
(5262 -863);
DISPLAY 0.340426 (5262 -863);
PAINT GREEN (5262 -863);
DISPLAY INVISIBLE (5262 -863);
FORCEPROP 2 LAST CDS_LIB mstr_symbols
J 0
(5250 -875);
DISPLAY 0.744681 (5250 -875);
PAINT ORANGE (5250 -875);
DISPLAY INVISIBLE (5250 -875);
FORCEPROP 2 LAST ROOM VDDQ_DEF_PWR_VR
J 0
(4800 4275);
DISPLAY 0.744681 (4800 4275);
PAINT ORANGE (4800 4275);
DISPLAY INVISIBLE (4800 4275);
FORCEPROP 2 LAST CDS_XR_PAGE_TITLE CR-218 : @BASEBOARD_FAB2_LIB.BASEBOARD_FAB2(SCH_1):PAGE218
J 0
(-2640 4375);
DISPLAY 0.638298 (-2640 4375);
PAINT PINK (-2640 4375);
DISPLAY INVISIBLE (-2640 4375);
WIRE 16 -1 (2150 3000)(2150 3350);
WIRE 16 -1 (2150 3350)(2350 3350);
WIRE 16 -1 (2350 3000)(2350 3350);
WIRE 16 -1 (2350 3350)(2550 3350);
WIRE 16 -1 (2650 3350)(2550 3350);
WIRE 16 -1 (2550 3350)(2550 3525);
WIRE 16 -1 (2650 2825)(2650 3350);
WIRE 16 -1 (2800 850)(2800 925);
WIRE 16 -1 (1775 900)(1900 900);
WIRE 16 -1 (1900 900)(1900 800);
WIRE 16 -1 (1775 800)(1900 800);
WIRE 16 -1 (1900 675)(1900 800);
WIRE 16 -1 (1425 2750)(1425 2800);
WIRE 16 -1 (1025 2750)(1025 2800);
WIRE 16 -1 (25 3425)(25 3600);
WIRE 16 -1 (25 3600)(725 3600);
WIRE 16 -1 (725 3350)(725 3600);
WIRE 16 -1 (725 3600)(725 3700);
WIRE 16 -1 (875 900)(0 900);
WIRE 16 -1 (0 900)(0 700);
WIRE 16 -1 (3525 -225)(3525 -100);
WIRE 16 -1 (3125 -150)(3125 -100);
WIRE 16 -1 (-75 -100)(-75 450);
WIRE 16 -1 (100 -100)(100 0);
WIRE 16 -1 (400 -100)(400 0);
WIRE 16 -1 (-725 3450)(-725 3725);
WIRE 16 -1 (-1350 3650)(-1350 3725);
WIRE 16 -1 (-1350 2975)(-1350 3075);
WIRE 16 -1 (-1575 2975)(-1575 3075);
WIRE 16 -1 (3700 2825)(3700 3400);
WIRE 16 -1 (-800 50)(-800 250);
WIRE 16 -1 (-1350 3375)(-1350 3450);
WIRE 16 -1 (-1350 3275)(-1350 3375);
WIRE 16 -1 (-1350 3375)(-1575 3375);
WIRE 16 -1 (-1575 3275)(-1575 3375);
WIRE 16 -1 (-1575 3375)(-2300 3375);
FORCEPROP 2 LAST SIG_NAME VR_PVDDQ_DEF_VINSEN
J 0
(-2240 3390);
DISPLAY 0.617021 (-2240 3390);
PAINT ORANGE (-2240 3390);
WIRE 16 -1 (3200 2350)(3875 2350);
FORCEPROP 2 LAST SIG_NAME PWRGD_PVDDQ_DEF
J 0
(3360 2365);
DISPLAY 0.617021 (3360 2365);
PAINT ORANGE (3360 2365);
WIRE 16 -1 (3875 2250)(3175 2250);
FORCEPROP 2 LAST SIG_NAME IRQ_PVDDQ_DEF_VRHOT_LVT3_N
J 0
(3160 2265);
DISPLAY 0.617021 (3160 2265);
PAINT ORANGE (3160 2265);
WIRE 16 -1 (2625 2200)(3875 2200);
FORCEPROP 2 LAST SIG_NAME SVID_ALERT1_CPU0_R_N
J 0
(3175 2210);
DISPLAY 0.617021 (3175 2210);
PAINT ORANGE (3175 2210);
WIRE 16 -1 (2650 2050)(2650 2625);
WIRE 16 -1 (2475 2050)(2650 2050);
WIRE 16 -1 (2475 2050)(2475 1700);
WIRE 16 -1 (1775 1700)(2475 1700);
FORCEPROP 2 LAST SIG_NAME PU_VR_PVDDQ_DEF_FAULT1
J 0
(1860 1715);
DISPLAY 0.617021 (1860 1715);
PAINT ORANGE (1860 1715);
FORCEPROP 2 LASTPROP $XRERR UNIQUE?
J 0
(1620 1715);
DISPLAY 0.638298 (1620 1715);
PAINT MONO (1620 1715);
DISPLAY INVISIBLE (1620 1715);
WIRE 16 -1 (2800 2350)(3000 2350);
WIRE 16 -1 (2350 2350)(2800 2350);
FORCEPROP 2 LAST SIG_NAME PWRGD_PVDDQ_DEF_R
J 0
(2410 2365);
DISPLAY 0.617021 (2410 2365);
PAINT ORANGE (2410 2365);
FORCEPROP 2 LASTPROP $XRERR UNIQUE?
J 0
(2170 2365);
DISPLAY 0.638298 (2170 2365);
PAINT MONO (2170 2365);
DISPLAY INVISIBLE (2170 2365);
WIRE 16 -1 (2800 2350)(2800 1125);
WIRE 16 -1 (2350 2800)(2350 2350);
WIRE 16 -1 (1775 2350)(2350 2350);
WIRE 16 -1 (2975 2250)(2150 2250);
FORCEPROP 2 LAST SIG_NAME IRQ_PVDDQ_DEF_VRHOT_LVT3_R_N
J 0
(1860 2265);
DISPLAY 0.617021 (1860 2265);
PAINT ORANGE (1860 2265);
FORCEPROP 2 LASTPROP $XRERR UNIQUE?
J 0
(1620 2265);
DISPLAY 0.638298 (1620 2265);
PAINT MONO (1620 2265);
DISPLAY INVISIBLE (1620 2265);
WIRE 16 -1 (2150 2800)(2150 2250);
WIRE 16 -1 (2150 2250)(1775 2250);
WIRE 16 -1 (3700 2625)(3700 1500);
WIRE 16 -1 (3700 1500)(3875 1500);
WIRE 16 -1 (2775 1500)(3700 1500);
FORCEPROP 2 LAST SIG_NAME SVID_DIO1_CPU0_R
J 0
(3225 1510);
DISPLAY 0.617021 (3225 1510);
PAINT ORANGE (3225 1510);
WIRE 16 -1 (3100 1850)(3875 1850);
FORCEPROP 2 LAST SIG_NAME SMB_VR_STBY_LVC3_SCL
J 0
(3335 1865);
DISPLAY 0.617021 (3335 1865);
PAINT ORANGE (3335 1865);
WIRE 16 -1 (3525 100)(3525 175);
WIRE 16 -1 (3525 175)(4050 175);
WIRE 16 -1 (3525 175)(3125 175);
FORCEPROP 2 LAST SIG_NAME VR_PVDDQ_DEF_VD12
J 0
(3210 190);
DISPLAY 0.617021 (3210 190);
PAINT ORANGE (3210 190);
WIRE 16 -1 (3125 100)(3125 175);
WIRE 16 -1 (2775 1800)(3875 1800);
FORCEPROP 2 LAST SIG_NAME SMB_VR_STBY_LVC3_SDA
J 0
(3335 1815);
DISPLAY 0.617021 (3335 1815);
PAINT ORANGE (3335 1815);
WIRE 16 -1 (1775 1650)(2475 1650);
FORCEPROP 2 LAST SIG_NAME TP_PVDDQ_DEF_MP1
J 0
(1875 1665);
DISPLAY 0.617021 (1875 1665);
PAINT ORANGE (1875 1665);
FORCEPROP 2 LASTPROP $XRERR UNIQUE?
J 0
(2505 1650);
DISPLAY 0.638298 (2505 1650);
PAINT MONO (2505 1650);
DISPLAY INVISIBLE (2505 1650);
WIRE 16 -1 (2425 2200)(1775 2200);
FORCEPROP 2 LAST SIG_NAME SVID_ALERT_PVDDQ_DEF
J 0
(1875 2215);
DISPLAY 0.617021 (1875 2215);
PAINT ORANGE (1875 2215);
FORCEPROP 2 LASTPROP $XRERR UNIQUE?
J 0
(1635 2215);
DISPLAY 0.638298 (1635 2215);
PAINT MONO (1635 2215);
DISPLAY INVISIBLE (1635 2215);
WIRE 16 -1 (1775 1050)(2550 1050);
FORCEPROP 2 LAST SIG_NAME NC_PVDDQ_DEF_DNC1
J 0
(1850 1065);
DISPLAY 0.617021 (1850 1065);
PAINT ORANGE (1850 1065);
FORCEPROP 2 LASTPROP $XRERR UNIQUE?
J 0
(2580 1050);
DISPLAY 0.638298 (2580 1050);
PAINT MONO (2580 1050);
DISPLAY INVISIBLE (2580 1050);
WIRE 16 -1 (1775 1000)(2550 1000);
FORCEPROP 2 LAST SIG_NAME NC_PVDDQ_DEF_DNC0
J 0
(1850 1015);
DISPLAY 0.617021 (1850 1015);
PAINT ORANGE (1850 1015);
FORCEPROP 2 LASTPROP $XRERR UNIQUE?
J 0
(2580 1000);
DISPLAY 0.638298 (2580 1000);
PAINT MONO (2580 1000);
DISPLAY INVISIBLE (2580 1000);
WIRE 16 -1 (1775 1500)(2575 1500);
FORCEPROP 2 LAST SIG_NAME SVID_VDIO_PVDDQ_DEF
J 0
(1875 1515);
DISPLAY 0.617021 (1875 1515);
PAINT ORANGE (1875 1515);
FORCEPROP 2 LASTPROP $XRERR UNIQUE?
J 0
(1635 1515);
DISPLAY 0.638298 (1635 1515);
PAINT MONO (1635 1515);
DISPLAY INVISIBLE (1635 1515);
WIRE 16 -1 (1775 1850)(2900 1850);
FORCEPROP 2 LAST SIG_NAME SMB_VR_SCL_VDDQ_DEF
J 0
(1875 1865);
DISPLAY 0.617021 (1875 1865);
PAINT ORANGE (1875 1865);
FORCEPROP 2 LASTPROP $XRERR UNIQUE?
J 0
(1635 1865);
DISPLAY 0.638298 (1635 1865);
PAINT MONO (1635 1865);
DISPLAY INVISIBLE (1635 1865);
WIRE 16 -1 (1775 1800)(2575 1800);
FORCEPROP 2 LAST SIG_NAME SMB_VR_SDA_VDDQ_DEF
J 0
(1875 1815);
DISPLAY 0.617021 (1875 1815);
PAINT ORANGE (1875 1815);
FORCEPROP 2 LASTPROP $XRERR UNIQUE?
J 0
(1635 1815);
DISPLAY 0.638298 (1635 1815);
PAINT MONO (1635 1815);
DISPLAY INVISIBLE (1635 1815);
WIRE 16 -1 (1775 1200)(2550 1200);
FORCEPROP 2 LAST SIG_NAME TP_PVDDQ_DEF_PWM3
J 0
(1850 1215);
DISPLAY 0.617021 (1850 1215);
PAINT ORANGE (1850 1215);
FORCEPROP 2 LASTPROP $XRERR UNIQUE?
J 0
(2580 1200);
DISPLAY 0.638298 (2580 1200);
PAINT MONO (2580 1200);
DISPLAY INVISIBLE (2580 1200);
WIRE 16 -1 (1775 1350)(2550 1350);
FORCEPROP 2 LAST SIG_NAME TP_PVDDQ_DEF_BPWM1
J 0
(1850 1365);
DISPLAY 0.617021 (1850 1365);
PAINT ORANGE (1850 1365);
FORCEPROP 2 LASTPROP $XRERR UNIQUE?
J 0
(2580 1350);
DISPLAY 0.638298 (2580 1350);
PAINT MONO (2580 1350);
DISPLAY INVISIBLE (2580 1350);
WIRE 16 -1 (1775 2050)(2325 2050);
FORCEPROP 2 LAST SIG_NAME TP_PVDDQ_DEF_MP2
J 0
(1875 2065);
DISPLAY 0.617021 (1875 2065);
PAINT ORANGE (1875 2065);
FORCEPROP 2 LASTPROP $XRERR UNIQUE?
J 0
(2355 2050);
DISPLAY 0.638298 (2355 2050);
PAINT MONO (2355 2050);
DISPLAY INVISIBLE (2355 2050);
WIRE 16 -1 (1775 1950)(2325 1950);
FORCEPROP 2 LAST SIG_NAME TP_PVDDQ_DEF_PINALRT_N
J 0
(1875 1965);
DISPLAY 0.617021 (1875 1965);
PAINT ORANGE (1875 1965);
FORCEPROP 2 LASTPROP $XRERR UNIQUE?
J 0
(2355 1950);
DISPLAY 0.638298 (2355 1950);
PAINT MONO (2355 1950);
DISPLAY INVISIBLE (2355 1950);
WIRE 16 -1 (3900 1550)(1775 1550);
FORCEPROP 2 LAST SIG_NAME VR_PVDDQ_DEF_VD12
J 0
(3210 1565);
DISPLAY 0.617021 (3210 1565);
PAINT ORANGE (3210 1565);
WIRE 16 -1 (3900 1300)(1775 1300);
FORCEPROP 2 LAST SIG_NAME VR_PVDDQ_DEF_PWM1
J 0
(3200 1315);
DISPLAY 0.617021 (3200 1315);
PAINT ORANGE (3200 1315);
WIRE 16 -1 (1775 1250)(3900 1250);
FORCEPROP 2 LAST SIG_NAME VR_PVDDQ_DEF_PWM2
J 0
(3200 1265);
DISPLAY 0.617021 (3200 1265);
PAINT ORANGE (3200 1265);
WIRE 16 2175 (2025 3825)(2025 3325);
WIRE 16 2175 (2025 3825)(1100 3825);
WIRE 16 2175 (2025 3325)(1100 3325);
WIRE 16 2175 (1100 3325)(1100 3825);
WIRE 16 -1 (1425 3000)(1425 3050);
WIRE 16 -1 (1425 3050)(1025 3050);
FORCEPROP 2 LAST SIG_NAME VR_PVDDQ_DEF_VDD
J 0
(985 3065);
DISPLAY 0.617021 (985 3065);
PAINT ORANGE (985 3065);
FORCEPROP 2 LASTPROP $XRERR UNIQUE?
J 0
(745 3065);
DISPLAY 0.638298 (745 3065);
PAINT MONO (745 3065);
DISPLAY INVISIBLE (745 3065);
WIRE 16 -1 (1025 3000)(1025 3050);
WIRE 16 -1 (1025 3050)(725 3050);
WIRE 16 -1 (725 3150)(725 3050);
WIRE 16 -1 (725 3050)(725 2350);
WIRE 16 -1 (875 2350)(725 2350);
WIRE 16 -1 (550 2825)(550 2250);
WIRE 16 -1 (-200 2825)(550 2825);
FORCEPROP 2 LAST SIG_NAME SVID_CLK_PVDDQ_DEF
J 0
(60 2840);
DISPLAY 0.617021 (60 2840);
PAINT ORANGE (60 2840);
FORCEPROP 2 LASTPROP $XRERR UNIQUE?
J 0
(-180 2840);
DISPLAY 0.638298 (-180 2840);
PAINT MONO (-180 2840);
DISPLAY INVISIBLE (-180 2840);
WIRE 16 -1 (550 2250)(875 2250);
WIRE 16 -1 (125 2050)(875 2050);
FORCEPROP 2 LAST SIG_NAME TP_PVDDQ_DEF_PH3_IMON_REF
J 0
(150 2065);
DISPLAY 0.617021 (150 2065);
PAINT ORANGE (150 2065);
FORCEPROP 2 LASTPROP $XRERR UNIQUE?
J 0
(-115 2050);
DISPLAY 0.638298 (-115 2050);
PAINT MONO (-115 2050);
DISPLAY INVISIBLE (-115 2050);
WIRE 16 -1 (25 1300)(25 3225);
WIRE 16 -1 (25 1300)(875 1300);
WIRE 16 -1 (-1625 1300)(25 1300);
FORCEPROP 2 LAST SIG_NAME VR_PVDDQ_DEF_VREN
J 0
(-700 1310);
DISPLAY 0.617021 (-700 1310);
PAINT ORANGE (-700 1310);
FORCEPROP 2 LASTPROP $XRERR UNIQUE?
J 0
(-940 1310);
DISPLAY 0.638298 (-940 1310);
PAINT MONO (-940 1310);
DISPLAY INVISIBLE (-940 1310);
WIRE 16 -1 (175 1150)(875 1150);
FORCEPROP 2 LAST SIG_NAME TP_PVDDQ_DEF_BVREF
J 0
(275 1165);
DISPLAY 0.617021 (275 1165);
PAINT ORANGE (275 1165);
FORCEPROP 2 LASTPROP $XRERR UNIQUE?
J 0
(-65 1150);
DISPLAY 0.638298 (-65 1150);
PAINT MONO (-65 1150);
DISPLAY INVISIBLE (-65 1150);
WIRE 16 -1 (175 1400)(875 1400);
FORCEPROP 2 LAST SIG_NAME TP_PVDDQ_DEF_BVSEN
J 0
(275 1415);
DISPLAY 0.617021 (275 1415);
PAINT ORANGE (275 1415);
FORCEPROP 2 LASTPROP $XRERR UNIQUE?
J 0
(-65 1400);
DISPLAY 0.638298 (-65 1400);
PAINT MONO (-65 1400);
DISPLAY INVISIBLE (-65 1400);
WIRE 16 -1 (175 1550)(875 1550);
FORCEPROP 2 LAST SIG_NAME TP_PVDDQ_DEF_BTSEN
J 0
(275 1565);
DISPLAY 0.617021 (275 1565);
PAINT ORANGE (275 1565);
FORCEPROP 2 LASTPROP $XRERR UNIQUE?
J 0
(-65 1550);
DISPLAY 0.638298 (-65 1550);
PAINT MONO (-65 1550);
DISPLAY INVISIBLE (-65 1550);
WIRE 16 -1 (875 1850)(150 1850);
FORCEPROP 2 LAST SIG_NAME TP_PVDDQ_DEF_PH3_IMON
J 0
(150 1865);
DISPLAY 0.617021 (150 1865);
PAINT ORANGE (150 1865);
FORCEPROP 2 LASTPROP $XRERR UNIQUE?
J 0
(-90 1850);
DISPLAY 0.638298 (-90 1850);
PAINT MONO (-90 1850);
DISPLAY INVISIBLE (-90 1850);
WIRE 16 -1 (175 1050)(875 1050);
FORCEPROP 2 LAST SIG_NAME TP_PVDDQ_DEF_RESET_N
J 0
(275 1065);
DISPLAY 0.617021 (275 1065);
PAINT ORANGE (275 1065);
FORCEPROP 2 LASTPROP $XRERR UNIQUE?
J 0
(-65 1050);
DISPLAY 0.638298 (-65 1050);
PAINT MONO (-65 1050);
DISPLAY INVISIBLE (-65 1050);
WIRE 16 -1 (175 950)(875 950);
FORCEPROP 2 LAST SIG_NAME TP_PVDDQ_DEF_BREF1
J 0
(275 965);
DISPLAY 0.617021 (275 965);
PAINT ORANGE (275 965);
FORCEPROP 2 LASTPROP $XRERR UNIQUE?
J 0
(-65 950);
DISPLAY 0.638298 (-65 950);
PAINT MONO (-65 950);
DISPLAY INVISIBLE (-65 950);
WIRE 16 -1 (100 800)(875 800);
WIRE 16 -1 (100 200)(100 800);
FORCEPROP 0 LAST SIG_NAME VR_PVDDQ_DEF_XADDR1
R 1
J 0
(90 235);
DISPLAY 0.617021 (90 235);
PAINT ORANGE (90 235);
FORCEPROP 2 LASTPROP $XRERR UNIQUE?
J 0
(-150 235);
DISPLAY 0.638298 (-150 235);
PAINT MONO (-150 235);
DISPLAY INVISIBLE (-150 235);
WIRE 16 -1 (400 750)(875 750);
WIRE 16 -1 (400 200)(400 750);
FORCEPROP 0 LAST SIG_NAME VR_PVDDQ_DEF_XADDR2
R 1
J 0
(390 210);
DISPLAY 0.617021 (390 210);
PAINT ORANGE (390 210);
FORCEPROP 2 LASTPROP $XRERR UNIQUE?
J 0
(150 210);
DISPLAY 0.638298 (150 210);
PAINT MONO (150 210);
DISPLAY INVISIBLE (150 210);
WIRE 16 -1 (875 1450)(-1000 1450);
WIRE 16 -1 (-1000 975)(-1000 1450);
WIRE 16 -1 (-1475 975)(-1000 975);
FORCEPROP 2 LAST SIG_NAME VR_PVDDQ_DEF_AVSP
J 0
(-1390 990);
DISPLAY 0.617021 (-1390 990);
PAINT ORANGE (-1390 990);
FORCEPROP 2 LASTPROP $XRERR UNIQUE?
J 0
(-1630 990);
DISPLAY 0.638298 (-1630 990);
PAINT MONO (-1630 990);
DISPLAY INVISIBLE (-1630 990);
WIRE 16 -1 (-1475 925)(-1475 975);
WIRE 16 -1 (-1650 975)(-1475 975);
WIRE 16 -1 (875 1200)(-950 1200);
WIRE 16 -1 (-950 1200)(-950 700);
WIRE 16 -1 (-950 700)(-1475 700);
WIRE 16 -1 (-1475 725)(-1475 700);
WIRE 16 -1 (-1475 700)(-2300 700);
FORCEPROP 2 LAST SIG_NAME VSENSE_PVDDQ_DEF_N
J 0
(-2315 715);
DISPLAY 0.617021 (-2315 715);
PAINT ORANGE (-2315 715);
WIRE 16 -1 (875 2150)(-1050 2150);
WIRE 16 -1 (-1050 2475)(-1050 2150);
WIRE 16 -1 (-2300 2150)(-1050 2150);
FORCEPROP 2 LAST SIG_NAME VR_PVDDQ_DEF_AIREF1
J 0
(-2290 2165);
DISPLAY 0.617021 (-2290 2165);
PAINT ORANGE (-2290 2165);
WIRE 16 -1 (-1300 2475)(-1050 2475);
WIRE 16 -1 (-400 2100)(875 2100);
WIRE 16 -1 (-400 2650)(-400 2100);
WIRE 16 -1 (-2300 2100)(-400 2100);
FORCEPROP 2 LAST SIG_NAME VR_PVDDQ_DEF_AIREF2
J 0
(-2290 2115);
DISPLAY 0.617021 (-2290 2115);
PAINT ORANGE (-2290 2115);
WIRE 16 -1 (-725 2650)(-400 2650);
WIRE 16 -1 (875 1700)(-800 1700);
WIRE 16 -1 (-800 450)(-800 1700);
WIRE 16 -1 (-800 1700)(-2300 1700);
FORCEPROP 2 LAST SIG_NAME VR_PVDDQ_DEF_AIINSEN
J 0
(-2310 1710);
DISPLAY 0.617021 (-2310 1710);
PAINT ORANGE (-2310 1710);
WIRE 16 -1 (-75 650)(-75 1600);
WIRE 16 -1 (-75 1600)(875 1600);
WIRE 16 -1 (-2300 1600)(-75 1600);
FORCEPROP 2 LAST SIG_NAME A_TSENSE_PVDDQ_DEF
J 0
(-2325 1615);
DISPLAY 0.617021 (-2325 1615);
PAINT ORANGE (-2325 1615);
WIRE 16 -1 (875 1950)(-2300 1950);
FORCEPROP 2 LAST SIG_NAME ISENSE_PVDDQ_DEF_PH1_IMON
J 0
(-2325 1965);
DISPLAY 0.617021 (-2325 1965);
PAINT ORANGE (-2325 1965);
WIRE 16 -1 (875 1900)(-2300 1900);
FORCEPROP 2 LAST SIG_NAME ISENSE_PVDDQ_DEF_PH2_IMON
J 0
(-2325 1915);
DISPLAY 0.617021 (-2325 1915);
PAINT ORANGE (-2325 1915);
WIRE 16 -1 (875 1750)(-2300 1750);
FORCEPROP 2 LAST SIG_NAME VR_PVDDQ_DEF_VINSEN
J 0
(-2325 1765);
DISPLAY 0.617021 (-2325 1765);
PAINT ORANGE (-2325 1765);
WIRE 16 -1 (-400 2825)(-725 2825);
WIRE 16 -1 (-725 3250)(-725 2825);
WIRE 16 -1 (-2325 2825)(-725 2825);
FORCEPROP 0 LAST SIG_NAME SVID_CLK1_CPU0_R
J 0
(-2325 2835);
DISPLAY 0.617021 (-2325 2835);
PAINT ORANGE (-2325 2835);
WIRE 16 -1 (-1750 2650)(-925 2650);
WIRE 16 -1 (-1750 2475)(-1750 2650);
WIRE 16 -1 (-1750 2475)(-1500 2475);
WIRE 16 -1 (-2275 2475)(-1750 2475);
FORCEPROP 2 LAST SIG_NAME VR_PVDDQ_DEF_VD12
J 0
(-2190 2490);
DISPLAY 0.617021 (-2190 2490);
PAINT ORANGE (-2190 2490);
WIRE 16 -1 (-1850 975)(-2325 975);
FORCEPROP 2 LAST SIG_NAME VSENSE_PVDDQ_DEF_P
J 0
(-2340 990);
DISPLAY 0.617021 (-2340 990);
PAINT ORANGE (-2340 990);
WIRE 16 -1 (-1825 1300)(-2300 1300);
FORCEPROP 2 LAST SIG_NAME FM_PVDDQ_DEF_EN
J 0
(-2275 1310);
DISPLAY 0.617021 (-2275 1310);
PAINT ORANGE (-2275 1310);
DOT 1 (-1475 700);
DOT 1 (-1475 975);
DOT 1 (-800 1700);
DOT 1 (-75 1600);
DOT 1 (-1750 2475);
DOT 1 (-1050 2150);
DOT 1 (-1575 3375);
DOT 1 (-1350 3375);
DOT 1 (-725 2825);
DOT 1 (-400 2100);
DOT 1 (25 1300);
DOT 1 (1900 800);
DOT 1 (725 3050);
DOT 1 (725 3600);
DOT 1 (1025 3050);
DOT 1 (3525 175);
DOT 1 (3700 1500);
DOT 1 (2150 2250);
DOT 1 (2350 2350);
DOT 1 (2800 2350);
DOT 1 (2350 3350);
DOT 1 (2550 3350);
FORCENOTE
ROOM=VDDQ_DEF_PWR_VR
(-2730 -715) 0;
DISPLAY LEFT (-2730 -715);
DISPLAY 2.446809 (-2730 -715);
PAINT PURPLE (-2730 -715);
FORCENOTE
SW FREQ = 833.33KHZ
(1125 3350) 0;
DISPLAY LEFT (1125 3350);
DISPLAY 0.808511 (1125 3350);
PAINT PURPLE (1125 3350);
FORCENOTE
IOUT PK = 74A
(1125 3500) 0;
DISPLAY LEFT (1125 3500);
DISPLAY 0.808511 (1125 3500);
PAINT PURPLE (1125 3500);
FORCENOTE
IOUT TDC = 63A
(1125 3550) 0;
DISPLAY LEFT (1125 3550);
DISPLAY 0.808511 (1125 3550);
PAINT PURPLE (1125 3550);
FORCENOTE
IOUT DI/DT = 15A/US
(1125 3400) 0;
DISPLAY LEFT (1125 3400);
DISPLAY 0.808511 (1125 3400);
PAINT PURPLE (1125 3400);
FORCENOTE
DC TOL = +/-0.5%
(1125 3650) 0;
DISPLAY LEFT (1125 3650);
DISPLAY 0.808511 (1125 3650);
PAINT PURPLE (1125 3650);
FORCENOTE
VOUT = 1.2V
(1125 3750) 0;
DISPLAY LEFT (1125 3750);
DISPLAY 0.808511 (1125 3750);
PAINT PURPLE (1125 3750);
FORCENOTE
IOUT STEP = 45A
(1125 3450) 0;
DISPLAY LEFT (1125 3450);
DISPLAY 0.808511 (1125 3450);
PAINT PURPLE (1125 3450);
FORCENOTE
AC & RIPPLE TOL = +/2.8%
(1125 3600) 0;
DISPLAY LEFT (1125 3600);
DISPLAY 0.808511 (1125 3600);
PAINT PURPLE (1125 3600);
FORCENOTE
RIPPLE GUIDELINE = +/- 0.5%
(1125 3700) 0;
DISPLAY LEFT (1125 3700);
DISPLAY 0.808511 (1125 3700);
PAINT PURPLE (1125 3700);
QUIT
